(lib_symbols
	(symbol "antmicroCapacitors0402:C_100n_0402"
			(pin_numbers hide)
			(pin_names hide)
			(exclude_from_sim no)
			(in_bom yes)
			(on_board yes)
			(property "Reference" "C"
				(at 20.32 -5.08 0)
				(effects
					(font
						(size 1.27 1.27)
						(thickness 0.15)
					)
					(justify left bottom)
				)
			)
			(property "Value" "C_100n_0402"
				(at 20.32 -10.16 0)
				(effects
					(font
						(size 1.27 1.27)
						(thickness 0.15)
					)
					(justify left bottom)
					(hide yes)
				)
			)
			(property "Footprint" "antmicro-footprints:C_0402_1005Metric"
				(at 20.32 -12.7 0)
				(effects
					(font
						(size 1.27 1.27)
						(thickness 0.15)
					)
					(justify left bottom)
					(hide yes)
				)
			)
			(property "Datasheet" "https://www.murata.com/products/productdetail?partno=GRM155R61H104KE14%23"
				(at 20.32 -15.24 0)
				(effects
					(font
						(size 1.27 1.27)
						(thickness 0.15)
					)
					(justify left bottom)
					(hide yes)
				)
			)
			(property "Description" "SMD Multilayer Ceramic Capacitor, 0.1 µF, 50 V, 0402 [1005 Metric], ± 10%, X5R, GRM Series"
				(at 0 0 0)
				(effects
					(font
						(size 1.27 1.27)
					)
					(hide yes)
				)
			)
			(property "MPN" "GRM155R61H104KE14D"
				(at 20.32 -17.78 0)
				(effects
					(font
						(size 1.27 1.27)
						(thickness 0.15)
					)
					(justify left bottom)
					(hide yes)
				)
			)
			(property "Manufacturer" "Murata"
				(at 20.32 -20.32 0)
				(effects
					(font
						(size 1.27 1.27)
						(thickness 0.15)
					)
					(justify left bottom)
					(hide yes)
				)
			)
			(property "License" "Apache-2.0"
				(at 20.32 -22.86 0)
				(effects
					(font
						(size 1.27 1.27)
						(thickness 0.15)
					)
					(justify left bottom)
					(hide yes)
				)
			)
			(property "Author" "Antmicro"
				(at 20.32 -25.4 0)
				(effects
					(font
						(size 1.27 1.27)
						(thickness 0.15)
					)
					(justify left bottom)
					(hide yes)
				)
			)
			(property "Val" "100n"
				(at 20.32 -7.62 0)
				(effects
					(font
						(size 1.27 1.27)
						(thickness 0.15)
					)
					(justify left bottom)
				)
			)
			(property "Voltage" "50V"
				(at 20.32 -27.94 0)
				(effects
					(font
						(size 1.27 1.27)
					)
					(justify left bottom)
					(hide yes)
				)
			)
			(property "Dielectric" "X5R"
				(at 20.32 -30.48 0)
				(effects
					(font
						(size 1.27 1.27)
					)
					(justify left bottom)
					(hide yes)
				)
			)
			(property "ki_keywords" "0402, SMT, CAPACITOR, PASSIVE, CERAMIC, MLCC"
				(at 0 0 0)
				(effects
					(font
						(size 1.27 1.27)
					)
					(hide yes)
				)
			)
			(symbol "C_100n_0402_0_1"
				(polyline
					(pts
						(xy 2.032 -1.524) (xy 2.032 1.524)
					)
					(stroke
						(width 0.3048)
						(type default)
					)
					(fill
						(type none)
					)
				)
				(polyline
					(pts
						(xy 3.048 -1.524) (xy 3.048 1.524)
					)
					(stroke
						(width 0.3302)
						(type default)
					)
					(fill
						(type none)
					)
				)
			)
			(symbol "C_100n_0402_1_1"
				(pin passive line
					(at 0 0 0)
					(length 2.032)
					(name "~"
						(effects
							(font
								(size 1.27 1.27)
							)
						)
					)
					(number "1"
						(effects
							(font
								(size 1.27 1.27)
							)
						)
					)
				)
				(pin passive line
					(at 5.08 0 180)
					(length 2.032)
					(name "~"
						(effects
							(font
								(size 1.27 1.27)
							)
						)
					)
					(number "2"
						(effects
							(font
								(size 1.27 1.27)
							)
						)
					)
				)
			)
		)
	(symbol "antmicroCapacitors0402:C_10n_0402"
			(pin_numbers hide)
			(pin_names hide)
			(exclude_from_sim no)
			(in_bom yes)
			(on_board yes)
			(property "Reference" "C"
				(at 20.32 -5.08 0)
				(effects
					(font
						(size 1.27 1.27)
						(thickness 0.15)
					)
					(justify left bottom)
				)
			)
			(property "Value" "C_10n_0402"
				(at 20.32 -10.16 0)
				(effects
					(font
						(size 1.27 1.27)
						(thickness 0.15)
					)
					(justify left bottom)
					(hide yes)
				)
			)
			(property "Footprint" "antmicro-footprints:C_0402_1005Metric"
				(at 20.32 -12.7 0)
				(effects
					(font
						(size 1.27 1.27)
						(thickness 0.15)
					)
					(justify left bottom)
					(hide yes)
				)
			)
			(property "Datasheet" "https://www.murata.com/products/productdetail?partno=GRM155R71H103KA88%23"
				(at 20.32 -15.24 0)
				(effects
					(font
						(size 1.27 1.27)
						(thickness 0.15)
					)
					(justify left bottom)
					(hide yes)
				)
			)
			(property "Description" "SMD Multilayer Ceramic Capacitor, 10000 pF, 50 V, 0402 [1005 Metric], ± 10%, X7R, GRM Series"
				(at 0 0 0)
				(effects
					(font
						(size 1.27 1.27)
					)
					(hide yes)
				)
			)
			(property "MPN" "GRM155R71H103KA88D"
				(at 20.32 -17.78 0)
				(effects
					(font
						(size 1.27 1.27)
						(thickness 0.15)
					)
					(justify left bottom)
					(hide yes)
				)
			)
			(property "Manufacturer" "Murata"
				(at 20.32 -20.32 0)
				(effects
					(font
						(size 1.27 1.27)
						(thickness 0.15)
					)
					(justify left bottom)
					(hide yes)
				)
			)
			(property "License" "Apache-2.0"
				(at 20.32 -22.86 0)
				(effects
					(font
						(size 1.27 1.27)
						(thickness 0.15)
					)
					(justify left bottom)
					(hide yes)
				)
			)
			(property "Author" "Antmicro"
				(at 20.32 -25.4 0)
				(effects
					(font
						(size 1.27 1.27)
						(thickness 0.15)
					)
					(justify left bottom)
					(hide yes)
				)
			)
			(property "Val" "10n"
				(at 20.32 -7.62 0)
				(effects
					(font
						(size 1.27 1.27)
						(thickness 0.15)
					)
					(justify left bottom)
				)
			)
			(property "Voltage" "50V"
				(at 20.32 -27.94 0)
				(effects
					(font
						(size 1.27 1.27)
					)
					(justify left bottom)
					(hide yes)
				)
			)
			(property "Dielectric" "X7R"
				(at 20.32 -30.48 0)
				(effects
					(font
						(size 1.27 1.27)
					)
					(justify left bottom)
					(hide yes)
				)
			)
			(property "ki_keywords" "0402, SMT, CAPACITOR, PASSIVE"
				(at 0 0 0)
				(effects
					(font
						(size 1.27 1.27)
					)
					(hide yes)
				)
			)
			(symbol "C_10n_0402_0_1"
				(polyline
					(pts
						(xy 2.032 -1.524) (xy 2.032 1.524)
					)
					(stroke
						(width 0.3048)
						(type default)
					)
					(fill
						(type none)
					)
				)
				(polyline
					(pts
						(xy 3.048 -1.524) (xy 3.048 1.524)
					)
					(stroke
						(width 0.3302)
						(type default)
					)
					(fill
						(type none)
					)
				)
			)
			(symbol "C_10n_0402_1_1"
				(pin passive line
					(at 0 0 0)
					(length 2.032)
					(name "~"
						(effects
							(font
								(size 1.27 1.27)
							)
						)
					)
					(number "1"
						(effects
							(font
								(size 1.27 1.27)
							)
						)
					)
				)
				(pin passive line
					(at 5.08 0 180)
					(length 2.032)
					(name "~"
						(effects
							(font
								(size 1.27 1.27)
							)
						)
					)
					(number "2"
						(effects
							(font
								(size 1.27 1.27)
							)
						)
					)
				)
			)
		)
	(symbol "antmicroCapacitors0402:C_10u_0402"
			(pin_numbers hide)
			(pin_names hide)
			(exclude_from_sim no)
			(in_bom yes)
			(on_board yes)
			(property "Reference" "C"
				(at 20.32 -5.08 0)
				(effects
					(font
						(size 1.27 1.27)
						(thickness 0.15)
					)
					(justify left bottom)
				)
			)
			(property "Value" "C_10u_0402"
				(at 20.32 -10.16 0)
				(effects
					(font
						(size 1.27 1.27)
						(thickness 0.15)
					)
					(justify left bottom)
					(hide yes)
				)
			)
			(property "Footprint" "antmicro-footprints:C_0402_1005Metric"
				(at 20.32 -12.7 0)
				(effects
					(font
						(size 1.27 1.27)
						(thickness 0.15)
					)
					(justify left bottom)
					(hide yes)
				)
			)
			(property "Datasheet" "https://www.yageo.com/en/Chart/Download/pdf/CC0402MRX5R5BB106"
				(at 20.32 -15.24 0)
				(effects
					(font
						(size 1.27 1.27)
						(thickness 0.15)
					)
					(justify left bottom)
					(hide yes)
				)
			)
			(property "Description" "SMD Multilayer Ceramic Capacitor, 10 µF, 6.3 V, 0402 [1005 Metric], ± 20%, X5R, CC Series"
				(at 0 0 0)
				(effects
					(font
						(size 1.27 1.27)
					)
					(hide yes)
				)
			)
			(property "MPN" "CC0402MRX5R5BB106"
				(at 20.32 -17.78 0)
				(effects
					(font
						(size 1.27 1.27)
						(thickness 0.15)
					)
					(justify left bottom)
					(hide yes)
				)
			)
			(property "Manufacturer" "YAGEO"
				(at 20.32 -20.32 0)
				(effects
					(font
						(size 1.27 1.27)
						(thickness 0.15)
					)
					(justify left bottom)
					(hide yes)
				)
			)
			(property "License" "Apache-2.0"
				(at 20.32 -22.86 0)
				(effects
					(font
						(size 1.27 1.27)
						(thickness 0.15)
					)
					(justify left bottom)
					(hide yes)
				)
			)
			(property "Author" "Antmicro"
				(at 20.32 -25.4 0)
				(effects
					(font
						(size 1.27 1.27)
						(thickness 0.15)
					)
					(justify left bottom)
					(hide yes)
				)
			)
			(property "Val" "10u"
				(at 20.32 -7.62 0)
				(effects
					(font
						(size 1.27 1.27)
						(thickness 0.15)
					)
					(justify left bottom)
				)
			)
			(property "Voltage" ""
				(at 20.32 -27.94 0)
				(effects
					(font
						(size 1.27 1.27)
					)
					(justify left bottom)
					(hide yes)
				)
			)
			(property "Dielectric" ""
				(at 20.32 -30.48 0)
				(effects
					(font
						(size 1.27 1.27)
					)
					(justify left bottom)
					(hide yes)
				)
			)
			(property "ki_keywords" "0402, SMT, CAPACITOR, PASSIVE, MLCC, CERAMIC"
				(at 0 0 0)
				(effects
					(font
						(size 1.27 1.27)
					)
					(hide yes)
				)
			)
			(symbol "C_10u_0402_0_1"
				(polyline
					(pts
						(xy 2.032 -1.524) (xy 2.032 1.524)
					)
					(stroke
						(width 0.3048)
						(type default)
					)
					(fill
						(type none)
					)
				)
				(polyline
					(pts
						(xy 3.048 -1.524) (xy 3.048 1.524)
					)
					(stroke
						(width 0.3302)
						(type default)
					)
					(fill
						(type none)
					)
				)
			)
			(symbol "C_10u_0402_1_1"
				(pin passive line
					(at 0 0 0)
					(length 2.032)
					(name "~"
						(effects
							(font
								(size 1.27 1.27)
							)
						)
					)
					(number "1"
						(effects
							(font
								(size 1.27 1.27)
							)
						)
					)
				)
				(pin passive line
					(at 5.08 0 180)
					(length 2.032)
					(name "~"
						(effects
							(font
								(size 1.27 1.27)
							)
						)
					)
					(number "2"
						(effects
							(font
								(size 1.27 1.27)
							)
						)
					)
				)
			)
		)
	(symbol "antmicroCapacitors0402:C_1u_16V_0402"
			(pin_numbers hide)
			(pin_names hide)
			(exclude_from_sim no)
			(in_bom yes)
			(on_board yes)
			(property "Reference" "C"
				(at 20.32 -5.08 0)
				(effects
					(font
						(size 1.27 1.27)
						(thickness 0.15)
					)
					(justify left bottom)
				)
			)
			(property "Value" "C_1u_16V_0402"
				(at 20.32 -10.16 0)
				(effects
					(font
						(size 1.27 1.27)
						(thickness 0.15)
					)
					(justify left bottom)
					(hide yes)
				)
			)
			(property "Footprint" "antmicro-footprints:C_0402_1005Metric"
				(at 20.32 -12.7 0)
				(effects
					(font
						(size 1.27 1.27)
						(thickness 0.15)
					)
					(justify left bottom)
					(hide yes)
				)
			)
			(property "Datasheet" "https://www.kemet.com/en/us/capacitors/product/C0402C105M4PACTU.html"
				(at 20.32 -15.24 0)
				(effects
					(font
						(size 1.27 1.27)
						(thickness 0.15)
					)
					(justify left bottom)
					(hide yes)
				)
			)
			(property "Description" "SMD Multilayer Ceramic Capacitor, 1 µF, 16 V, 0402 [1005 Metric], ± 20%, X5R, C Series KEMET"
				(at 0 0 0)
				(effects
					(font
						(size 1.27 1.27)
					)
					(hide yes)
				)
			)
			(property "MPN" "C0402C105M4PACTU"
				(at 20.32 -17.78 0)
				(effects
					(font
						(size 1.27 1.27)
						(thickness 0.15)
					)
					(justify left bottom)
					(hide yes)
				)
			)
			(property "Manufacturer" "KEMET"
				(at 20.32 -20.32 0)
				(effects
					(font
						(size 1.27 1.27)
						(thickness 0.15)
					)
					(justify left bottom)
					(hide yes)
				)
			)
			(property "License" "Apache-2.0"
				(at 20.32 -22.86 0)
				(effects
					(font
						(size 1.27 1.27)
						(thickness 0.15)
					)
					(justify left bottom)
					(hide yes)
				)
			)
			(property "Author" "Antmicro"
				(at 20.32 -25.4 0)
				(effects
					(font
						(size 1.27 1.27)
						(thickness 0.15)
					)
					(justify left bottom)
					(hide yes)
				)
			)
			(property "Val" "1u"
				(at 20.32 -7.62 0)
				(effects
					(font
						(size 1.27 1.27)
						(thickness 0.15)
					)
					(justify left bottom)
				)
			)
			(property "Voltage" "16V"
				(at 20.32 -27.94 0)
				(effects
					(font
						(size 1.27 1.27)
					)
					(justify left bottom)
					(hide yes)
				)
			)
			(property "Dielectric" ""
				(at 20.32 -30.48 0)
				(effects
					(font
						(size 1.27 1.27)
					)
					(justify left bottom)
					(hide yes)
				)
			)
			(property "ki_keywords" "0402, SMT, CAPACITOR, PASSIVE, CERAMIC"
				(at 0 0 0)
				(effects
					(font
						(size 1.27 1.27)
					)
					(hide yes)
				)
			)
			(symbol "C_1u_16V_0402_0_1"
				(polyline
					(pts
						(xy 2.032 -1.524) (xy 2.032 1.524)
					)
					(stroke
						(width 0.3048)
						(type default)
					)
					(fill
						(type none)
					)
				)
				(polyline
					(pts
						(xy 3.048 -1.524) (xy 3.048 1.524)
					)
					(stroke
						(width 0.3302)
						(type default)
					)
					(fill
						(type none)
					)
				)
			)
			(symbol "C_1u_16V_0402_1_1"
				(pin passive line
					(at 0 0 0)
					(length 2.032)
					(name "~"
						(effects
							(font
								(size 1.27 1.27)
							)
						)
					)
					(number "1"
						(effects
							(font
								(size 1.27 1.27)
							)
						)
					)
				)
				(pin passive line
					(at 5.08 0 180)
					(length 2.032)
					(name "~"
						(effects
							(font
								(size 1.27 1.27)
							)
						)
					)
					(number "2"
						(effects
							(font
								(size 1.27 1.27)
							)
						)
					)
				)
			)
		)
	(symbol "antmicroCapacitors0402:C_220n_0402"
			(pin_numbers hide)
			(pin_names hide)
			(exclude_from_sim no)
			(in_bom yes)
			(on_board yes)
			(property "Reference" "C"
				(at 20.32 -5.08 0)
				(effects
					(font
						(size 1.27 1.27)
						(thickness 0.15)
					)
					(justify left bottom)
				)
			)
			(property "Value" "C_220n_0402"
				(at 20.32 -10.16 0)
				(effects
					(font
						(size 1.27 1.27)
						(thickness 0.15)
					)
					(justify left bottom)
					(hide yes)
				)
			)
			(property "Footprint" "antmicro-footprints:C_0402_1005Metric"
				(at 20.32 -12.7 0)
				(effects
					(font
						(size 1.27 1.27)
						(thickness 0.15)
					)
					(justify left bottom)
					(hide yes)
				)
			)
			(property "Datasheet" "https://www.yageo.com/en/Chart/Download/pdf/CC0402KRX5R6BB224"
				(at 20.32 -15.24 0)
				(effects
					(font
						(size 1.27 1.27)
						(thickness 0.15)
					)
					(justify left bottom)
					(hide yes)
				)
			)
			(property "Description" "SMD Multilayer Ceramic Capacitor, 0.22 µF, 10 V, 0402 [1005 Metric], ± 10%, X5R, CC Series"
				(at 0 0 0)
				(effects
					(font
						(size 1.27 1.27)
					)
					(hide yes)
				)
			)
			(property "MPN" "CC0402KRX5R6BB224"
				(at 20.32 -17.78 0)
				(effects
					(font
						(size 1.27 1.27)
						(thickness 0.15)
					)
					(justify left bottom)
					(hide yes)
				)
			)
			(property "Manufacturer" "YAGEO"
				(at 20.32 -20.32 0)
				(effects
					(font
						(size 1.27 1.27)
						(thickness 0.15)
					)
					(justify left bottom)
					(hide yes)
				)
			)
			(property "License" "Apache-2.0"
				(at 20.32 -22.86 0)
				(effects
					(font
						(size 1.27 1.27)
						(thickness 0.15)
					)
					(justify left bottom)
					(hide yes)
				)
			)
			(property "Author" "Antmicro"
				(at 20.32 -25.4 0)
				(effects
					(font
						(size 1.27 1.27)
						(thickness 0.15)
					)
					(justify left bottom)
					(hide yes)
				)
			)
			(property "Val" "220n"
				(at 20.32 -7.62 0)
				(effects
					(font
						(size 1.27 1.27)
						(thickness 0.15)
					)
					(justify left bottom)
				)
			)
			(property "Voltage" ""
				(at 20.32 -27.94 0)
				(effects
					(font
						(size 1.27 1.27)
					)
					(justify left bottom)
					(hide yes)
				)
			)
			(property "Dielectric" ""
				(at 20.32 -30.48 0)
				(effects
					(font
						(size 1.27 1.27)
					)
					(justify left bottom)
					(hide yes)
				)
			)
			(property "ki_keywords" "0402, SMT, CAPACITOR, PASSIVE, MLCC, CERAMIC"
				(at 0 0 0)
				(effects
					(font
						(size 1.27 1.27)
					)
					(hide yes)
				)
			)
			(symbol "C_220n_0402_0_1"
				(polyline
					(pts
						(xy 2.032 -1.524) (xy 2.032 1.524)
					)
					(stroke
						(width 0.3048)
						(type default)
					)
					(fill
						(type none)
					)
				)
				(polyline
					(pts
						(xy 3.048 -1.524) (xy 3.048 1.524)
					)
					(stroke
						(width 0.3302)
						(type default)
					)
					(fill
						(type none)
					)
				)
			)
			(symbol "C_220n_0402_1_1"
				(pin passive line
					(at 0 0 0)
					(length 2.032)
					(name "~"
						(effects
							(font
								(size 1.27 1.27)
							)
						)
					)
					(number "1"
						(effects
							(font
								(size 1.27 1.27)
							)
						)
					)
				)
				(pin passive line
					(at 5.08 0 180)
					(length 2.032)
					(name "~"
						(effects
							(font
								(size 1.27 1.27)
							)
						)
					)
					(number "2"
						(effects
							(font
								(size 1.27 1.27)
							)
						)
					)
				)
			)
		)
	(symbol "antmicroCapacitors0402:C_22u_0402"
			(pin_numbers hide)
			(pin_names hide)
			(exclude_from_sim no)
			(in_bom yes)
			(on_board yes)
			(property "Reference" "C"
				(at 20.32 -5.08 0)
				(effects
					(font
						(size 1.27 1.27)
						(thickness 0.15)
					)
					(justify left bottom)
				)
			)
			(property "Value" "C_22u_0402"
				(at 20.32 -10.16 0)
				(effects
					(font
						(size 1.27 1.27)
						(thickness 0.15)
					)
					(justify left bottom)
					(hide yes)
				)
			)
			(property "Footprint" "antmicro-footprints:C_0402_1005Metric"
				(at 20.32 -12.7 0)
				(effects
					(font
						(size 1.27 1.27)
						(thickness 0.15)
					)
					(justify left bottom)
					(hide yes)
				)
			)
			(property "Datasheet" "https://www.murata.com/products/productdetail?partno=GRM158R60J226ME01%23"
				(at 20.32 -15.24 0)
				(effects
					(font
						(size 1.27 1.27)
						(thickness 0.15)
					)
					(justify left bottom)
					(hide yes)
				)
			)
			(property "Description" "SMD Multilayer Ceramic Capacitor, 22 uF, 4 V, 0402 [1005 Metric], X6S"
				(at 0 0 0)
				(effects
					(font
						(size 1.27 1.27)
					)
					(hide yes)
				)
			)
			(property "MPN" "GRM158R60J226ME01D"
				(at 20.32 -17.78 0)
				(effects
					(font
						(size 1.27 1.27)
						(thickness 0.15)
					)
					(justify left bottom)
					(hide yes)
				)
			)
			(property "Manufacturer" "Murata"
				(at 20.32 -20.32 0)
				(effects
					(font
						(size 1.27 1.27)
						(thickness 0.15)
					)
					(justify left bottom)
					(hide yes)
				)
			)
			(property "License" "Apache-2.0"
				(at 20.32 -22.86 0)
				(effects
					(font
						(size 1.27 1.27)
						(thickness 0.15)
					)
					(justify left bottom)
					(hide yes)
				)
			)
			(property "Author" "Antmicro"
				(at 20.32 -25.4 0)
				(effects
					(font
						(size 1.27 1.27)
						(thickness 0.15)
					)
					(justify left bottom)
					(hide yes)
				)
			)
			(property "Val" "22u"
				(at 20.32 -7.62 0)
				(effects
					(font
						(size 1.27 1.27)
						(thickness 0.15)
					)
					(justify left bottom)
				)
			)
			(property "Voltage" ""
				(at 20.32 -27.94 0)
				(effects
					(font
						(size 1.27 1.27)
					)
					(justify left bottom)
					(hide yes)
				)
			)
			(property "Dielectric" ""
				(at 20.32 -30.48 0)
				(effects
					(font
						(size 1.27 1.27)
					)
					(justify left bottom)
					(hide yes)
				)
			)
			(property "ki_keywords" "1210, SMT, CAPACITOR, PASSIVE, CERAMIC, MLCC"
				(at 0 0 0)
				(effects
					(font
						(size 1.27 1.27)
					)
					(hide yes)
				)
			)
			(symbol "C_22u_0402_0_1"
				(polyline
					(pts
						(xy 2.032 -1.524) (xy 2.032 1.524)
					)
					(stroke
						(width 0.3048)
						(type default)
					)
					(fill
						(type none)
					)
				)
				(polyline
					(pts
						(xy 3.048 -1.524) (xy 3.048 1.524)
					)
					(stroke
						(width 0.3302)
						(type default)
					)
					(fill
						(type none)
					)
				)
			)
			(symbol "C_22u_0402_1_1"
				(pin passive line
					(at 0 0 0)
					(length 2.032)
					(name "~"
						(effects
							(font
								(size 1.27 1.27)
							)
						)
					)
					(number "1"
						(effects
							(font
								(size 1.27 1.27)
							)
						)
					)
				)
				(pin passive line
					(at 5.08 0 180)
					(length 2.032)
					(name "~"
						(effects
							(font
								(size 1.27 1.27)
							)
						)
					)
					(number "2"
						(effects
							(font
								(size 1.27 1.27)
							)
						)
					)
				)
			)
		)
	(symbol "antmicroCapacitors0402:C_33p_0402"
			(pin_numbers hide)
			(pin_names hide)
			(exclude_from_sim no)
			(in_bom yes)
			(on_board yes)
			(property "Reference" "C"
				(at 20.32 -5.08 0)
				(effects
					(font
						(size 1.27 1.27)
						(thickness 0.15)
					)
					(justify left bottom)
				)
			)
			(property "Value" "C_33p_0402"
				(at 20.32 -10.16 0)
				(effects
					(font
						(size 1.27 1.27)
						(thickness 0.15)
					)
					(justify left bottom)
					(hide yes)
				)
			)
			(property "Footprint" "antmicro-footprints:C_0402_1005Metric"
				(at 20.32 -12.7 0)
				(effects
					(font
						(size 1.27 1.27)
						(thickness 0.15)
					)
					(justify left bottom)
					(hide yes)
				)
			)
			(property "Datasheet" "https://spicat.kyocera-avx.com/product/mlcc/chartview/04025A330FAT2A/"
				(at 20.32 -15.24 0)
				(effects
					(font
						(size 1.27 1.27)
						(thickness 0.15)
					)
					(justify left bottom)
					(hide yes)
				)
			)
			(property "Description" "SMD Multilayer Ceramic Capacitor, 33 pF, 50 V, 0402 [1005 Metric], ± 5%, C0G / NP0, MC"
				(at 0 0 0)
				(effects
					(font
						(size 1.27 1.27)
					)
					(hide yes)
				)
			)
			(property "MPN" "04025A330FAT2A"
				(at 20.32 -17.78 0)
				(effects
					(font
						(size 1.27 1.27)
						(thickness 0.15)
					)
					(justify left bottom)
					(hide yes)
				)
			)
			(property "Manufacturer" "KYOCERA AVX"
				(at 20.32 -20.32 0)
				(effects
					(font
						(size 1.27 1.27)
						(thickness 0.15)
					)
					(justify left bottom)
					(hide yes)
				)
			)
			(property "License" "Apache-2.0"
				(at 20.32 -22.86 0)
				(effects
					(font
						(size 1.27 1.27)
						(thickness 0.15)
					)
					(justify left bottom)
					(hide yes)
				)
			)
			(property "Author" "Antmicro"
				(at 20.32 -25.4 0)
				(effects
					(font
						(size 1.27 1.27)
						(thickness 0.15)
					)
					(justify left bottom)
					(hide yes)
				)
			)
			(property "Val" "33p"
				(at 20.32 -7.62 0)
				(effects
					(font
						(size 1.27 1.27)
						(thickness 0.15)
					)
					(justify left bottom)
				)
			)
			(property "Voltage" ""
				(at 20.32 -27.94 0)
				(effects
					(font
						(size 1.27 1.27)
					)
					(justify left bottom)
					(hide yes)
				)
			)
			(property "Dielectric" ""
				(at 20.32 -30.48 0)
				(effects
					(font
						(size 1.27 1.27)
					)
					(justify left bottom)
					(hide yes)
				)
			)
			(property "ki_keywords" "0402, SMT, CAPACITOR, PASSIVE"
				(at 0 0 0)
				(effects
					(font
						(size 1.27 1.27)
					)
					(hide yes)
				)
			)
			(symbol "C_33p_0402_0_1"
				(polyline
					(pts
						(xy 2.032 -1.524) (xy 2.032 1.524)
					)
					(stroke
						(width 0.3048)
						(type default)
					)
					(fill
						(type none)
					)
				)
				(polyline
					(pts
						(xy 3.048 -1.524) (xy 3.048 1.524)
					)
					(stroke
						(width 0.3302)
						(type default)
					)
					(fill
						(type none)
					)
				)
			)
			(symbol "C_33p_0402_1_1"
				(pin passive line
					(at 0 0 0)
					(length 2.032)
					(name "~"
						(effects
							(font
								(size 1.27 1.27)
							)
						)
					)
					(number "1"
						(effects
							(font
								(size 1.27 1.27)
							)
						)
					)
				)
				(pin passive line
					(at 5.08 0 180)
					(length 2.032)
					(name "~"
						(effects
							(font
								(size 1.27 1.27)
							)
						)
					)
					(number "2"
						(effects
							(font
								(size 1.27 1.27)
							)
						)
					)
				)
			)
		)
	(symbol "antmicroCapacitors0603:C_10u_25V_0603"
			(pin_numbers hide)
			(pin_names hide)
			(exclude_from_sim no)
			(in_bom yes)
			(on_board yes)
			(property "Reference" "C"
				(at 20.32 -5.08 0)
				(effects
					(font
						(size 1.27 1.27)
						(thickness 0.15)
					)
					(justify left bottom)
				)
			)
			(property "Value" "C_10u_25V_0603"
				(at 20.32 -10.16 0)
				(effects
					(font
						(size 1.27 1.27)
						(thickness 0.15)
					)
					(justify left bottom)
					(hide yes)
				)
			)
			(property "Footprint" "antmicro-footprints:C_0603_1608Metric"
				(at 20.32 -12.7 0)
				(effects
					(font
						(size 1.27 1.27)
						(thickness 0.15)
					)
					(justify left bottom)
					(hide yes)
				)
			)
			(property "Datasheet" "https://product.tdk.com/en/search/capacitor/ceramic/mlcc/info?part_no=C1608X5R1E106M080AC"
				(at 20.32 -15.24 0)
				(effects
					(font
						(size 1.27 1.27)
						(thickness 0.15)
					)
					(justify left bottom)
					(hide yes)
				)
			)
			(property "Description" "SMD Multilayer Ceramic Capacitor, 10 µF, 25 V, 0603 [1608 Metric], ± 20%, X5R, C"
				(at 0 0 0)
				(effects
					(font
						(size 1.27 1.27)
					)
					(hide yes)
				)
			)
			(property "MPN" "C1608X5R1E106M080AC"
				(at 20.32 -17.78 0)
				(effects
					(font
						(size 1.27 1.27)
						(thickness 0.15)
					)
					(justify left bottom)
					(hide yes)
				)
			)
			(property "Manufacturer" "TDK"
				(at 20.32 -20.32 0)
				(effects
					(font
						(size 1.27 1.27)
						(thickness 0.15)
					)
					(justify left bottom)
					(hide yes)
				)
			)
			(property "License" "Apache-2.0"
				(at 20.32 -22.86 0)
				(effects
					(font
						(size 1.27 1.27)
						(thickness 0.15)
					)
					(justify left bottom)
					(hide yes)
				)
			)
			(property "Author" "Antmicro"
				(at 20.32 -25.4 0)
				(effects
					(font
						(size 1.27 1.27)
						(thickness 0.15)
					)
					(justify left bottom)
					(hide yes)
				)
			)
			(property "Val" "10u"
				(at 20.32 -7.62 0)
				(effects
					(font
						(size 1.27 1.27)
						(thickness 0.15)
					)
					(justify left bottom)
				)
			)
			(property "Voltage" "25V"
				(at 20.32 -27.94 0)
				(effects
					(font
						(size 1.27 1.27)
					)
					(justify left bottom)
					(hide yes)
				)
			)
			(property "Dielectric" ""
				(at 20.32 -30.48 0)
				(effects
					(font
						(size 1.27 1.27)
					)
					(justify left bottom)
					(hide yes)
				)
			)
			(property "ki_keywords" "0603, SMT, CAPACITOR, PASSIVE, CERAMIC, MLCC"
				(at 0 0 0)
				(effects
					(font
						(size 1.27 1.27)
					)
					(hide yes)
				)
			)
			(symbol "C_10u_25V_0603_0_1"
				(polyline
					(pts
						(xy 2.032 -1.524) (xy 2.032 1.524)
					)
					(stroke
						(width 0.3048)
						(type default)
					)
					(fill
						(type none)
					)
				)
				(polyline
					(pts
						(xy 3.048 -1.524) (xy 3.048 1.524)
					)
					(stroke
						(width 0.3302)
						(type default)
					)
					(fill
						(type none)
					)
				)
			)
			(symbol "C_10u_25V_0603_1_1"
				(pin passive line
					(at 0 0 0)
					(length 2.032)
					(name "~"
						(effects
							(font
								(size 1.27 1.27)
							)
						)
					)
					(number "1"
						(effects
							(font
								(size 1.27 1.27)
							)
						)
					)
				)
				(pin passive line
					(at 5.08 0 180)
					(length 2.032)
					(name "~"
						(effects
							(font
								(size 1.27 1.27)
							)
						)
					)
					(number "2"
						(effects
							(font
								(size 1.27 1.27)
							)
						)
					)
				)
			)
		)
	(symbol "antmicroCoaxialConnectorsRF:Conn_FAKRA_59S2AQ-40MT5-Z_1"
			(pin_names hide)
			(exclude_from_sim no)
			(in_bom yes)
			(on_board yes)
			(property "Reference" "J"
				(at 20.32 -5.08 0)
				(effects
					(font
						(size 1.27 1.27)
						(thickness 0.15)
					)
					(justify left bottom)
				)
			)
			(property "Value" "Conn_FAKRA_59S2AQ-40MT5-Z_1"
				(at 20.32 -7.62 0)
				(effects
					(font
						(size 1.27 1.27)
						(thickness 0.15)
					)
					(justify left bottom)
					(hide yes)
				)
			)
			(property "Footprint" "antmicro-footprints:Conn_FAKRA_59S2AQ-40MT5-Z_1"
				(at 20.32 -10.16 0)
				(effects
					(font
						(size 1.27 1.27)
						(thickness 0.15)
					)
					(justify left bottom)
					(hide yes)
				)
			)
			(property "Datasheet" "https://products.rosenberger.com/radio-frequency/connectors/288881/59s2aq-40mt5-z-1-right-angle-plug-pcb-w.-housing"
				(at 20.32 -12.7 0)
				(effects
					(font
						(size 1.27 1.27)
						(thickness 0.15)
					)
					(justify left bottom)
					(hide yes)
				)
			)
			(property "Description" "FAKRA GEN 2 PCB, SMD, Right angle plug, 50 Ohm, Z Key Code"
				(at 0 0 0)
				(effects
					(font
						(size 1.27 1.27)
					)
					(hide yes)
				)
			)
			(property "MPN" "59S2AQ-40MT5-Z_1"
				(at 20.32 -15.24 0)
				(effects
					(font
						(size 1.27 1.27)
						(thickness 0.15)
					)
					(justify left bottom)
				)
			)
			(property "Manufacturer" "Rosenberger"
				(at 20.32 -17.78 0)
				(effects
					(font
						(size 1.27 1.27)
						(thickness 0.15)
					)
					(justify left bottom)
					(hide yes)
				)
			)
			(property "Author" "Antmicro"
				(at 20.32 -20.32 0)
				(effects
					(font
						(size 1.27 1.27)
						(thickness 0.15)
					)
					(justify left bottom)
					(hide yes)
				)
			)
			(property "License" "Apache-2.0"
				(at 20.32 -22.86 0)
				(effects
					(font
						(size 1.27 1.27)
						(thickness 0.15)
					)
					(justify left bottom)
					(hide yes)
				)
			)
			(property "ki_keywords" "CONNECTOR"
				(at 0 0 0)
				(effects
					(font
						(size 1.27 1.27)
					)
					(hide yes)
				)
			)
			(property "ki_fp_filters" "*BNC* *SMA* *SMB* *SMC* *Cinch*"
				(at 0 0 0)
				(effects
					(font
						(size 1.27 1.27)
					)
					(hide yes)
				)
			)
			(symbol "Conn_FAKRA_59S2AQ-40MT5-Z_1_1_1"
				(polyline
					(pts
						(xy 2.54 0) (xy 4.572 0)
					)
					(stroke
						(width 0.254)
						(type default)
					)
					(fill
						(type none)
					)
				)
				(polyline
					(pts
						(xy 5.08 -2.54) (xy 5.08 -1.778)
					)
					(stroke
						(width 0.254)
						(type default)
					)
					(fill
						(type none)
					)
				)
				(arc
					(start 3.302 -0.508)
					(mid 5.302 -1.808)
					(end 6.858 0)
					(stroke
						(width 0.254)
						(type default)
					)
					(fill
						(type none)
					)
				)
				(circle
					(center 5.08 0)
					(radius 0.508)
					(stroke
						(width 0.254)
						(type default)
					)
					(fill
						(type none)
					)
				)
				(arc
					(start 6.858 0)
					(mid 5.302 1.8083)
					(end 3.302 0.508)
					(stroke
						(width 0.254)
						(type default)
					)
					(fill
						(type none)
					)
				)
				(pin passive line
					(at 0 0 0)
					(length 2.54)
					(name "1"
						(effects
							(font
								(size 1.27 1.27)
							)
						)
					)
					(number "1"
						(effects
							(font
								(size 1.27 1.27)
							)
						)
					)
				)
				(pin passive line
					(at 5.08 -5.08 90)
					(length 2.54)
					(name "2"
						(effects
							(font
								(size 1.27 1.27)
							)
						)
					)
					(number "2"
						(effects
							(font
								(size 1.27 1.27)
							)
						)
					)
				)
				(pin passive line
					(at 5.08 -5.08 90)
					(length 2.54) hide
					(name "3"
						(effects
							(font
								(size 1.27 1.27)
							)
						)
					)
					(number "3"
						(effects
							(font
								(size 1.27 1.27)
							)
						)
					)
				)
				(pin passive line
					(at 5.08 -5.08 90)
					(length 2.54) hide
					(name "4"
						(effects
							(font
								(size 1.27 1.27)
							)
						)
					)
					(number "4"
						(effects
							(font
								(size 1.27 1.27)
							)
						)
					)
				)
				(pin passive line
					(at 5.08 -5.08 90)
					(length 2.54) hide
					(name "5"
						(effects
							(font
								(size 1.27 1.27)
							)
						)
					)
					(number "5"
						(effects
							(font
								(size 1.27 1.27)
							)
						)
					)
				)
			)
		)
	(symbol "antmicroDCDCConverters:AP62301_TSOT"
			(exclude_from_sim no)
			(in_bom yes)
			(on_board yes)
			(property "Reference" "U"
				(at 35.56 -2.54 0)
				(effects
					(font
						(size 1.27 1.27)
						(thickness 0.15)
					)
					(justify left bottom)
				)
			)
			(property "Value" "AP62301_TSOT"
				(at 35.56 -7.62 0)
				(effects
					(font
						(size 1.27 1.27)
						(thickness 0.15)
					)
					(justify left bottom)
					(hide yes)
				)
			)
			(property "Footprint" "antmicro-footprints:TSOT23-6"
				(at 35.56 -10.16 0)
				(effects
					(font
						(size 1.27 1.27)
						(thickness 0.15)
					)
					(justify left bottom)
					(hide yes)
				)
			)
			(property "Datasheet" "https://www.diodes.com/assets/Datasheets/AP62300_AP62301_AP62300T.pdf"
				(at 35.56 -12.7 0)
				(effects
					(font
						(size 1.27 1.27)
						(thickness 0.15)
					)
					(justify left bottom)
					(hide yes)
				)
			)
			(property "Description" "DC-DC Switching Synchronous Buck Regulator, Adjustable, 4.2V-18Vin, 0.8V-7V/3A out, TSOT-26-6"
				(at 0 0 0)
				(effects
					(font
						(size 1.27 1.27)
					)
					(hide yes)
				)
			)
			(property "MPN" "AP62301WU-7"
				(at 35.56 -5.08 0)
				(effects
					(font
						(size 1.27 1.27)
						(thickness 0.15)
					)
					(justify left bottom)
				)
			)
			(property "Manufacturer" "Diodes Incorporated"
				(at 35.56 -15.24 0)
				(effects
					(font
						(size 1.27 1.27)
						(thickness 0.15)
					)
					(justify left bottom)
					(hide yes)
				)
			)
			(property "Author" "Antmicro"
				(at 35.56 -17.78 0)
				(effects
					(font
						(size 1.27 1.27)
						(thickness 0.15)
					)
					(justify left bottom)
					(hide yes)
				)
			)
			(property "License" "Apache-2.0"
				(at 35.56 -20.32 0)
				(effects
					(font
						(size 1.27 1.27)
						(thickness 0.15)
					)
					(justify left bottom)
					(hide yes)
				)
			)
			(property "ki_keywords" "SMT, PMIC, IC, VOLTAGE"
				(at 0 0 0)
				(effects
					(font
						(size 1.27 1.27)
					)
					(hide yes)
				)
			)
			(symbol "AP62301_TSOT_1_1"
				(rectangle
					(start 2.54 2.54)
					(end 17.78 -12.7)
					(stroke
						(width 0.254)
						(type default)
					)
					(fill
						(type background)
					)
				)
				(pin power_in line
					(at 0 -10.16 0)
					(length 2.54)
					(name "GND"
						(effects
							(font
								(size 1.27 1.27)
							)
						)
					)
					(number "1"
						(effects
							(font
								(size 1.27 1.27)
							)
						)
					)
				)
				(pin power_out line
					(at 20.32 0 180)
					(length 2.54)
					(name "SW"
						(effects
							(font
								(size 1.27 1.27)
							)
						)
					)
					(number "2"
						(effects
							(font
								(size 1.27 1.27)
							)
						)
					)
				)
				(pin power_in line
					(at 0 0 0)
					(length 2.54)
					(name "VIN"
						(effects
							(font
								(size 1.27 1.27)
							)
						)
					)
					(number "3"
						(effects
							(font
								(size 1.27 1.27)
							)
						)
					)
				)
				(pin input line
					(at 20.32 -10.16 180)
					(length 2.54)
					(name "FB"
						(effects
							(font
								(size 1.27 1.27)
							)
						)
					)
					(number "4"
						(effects
							(font
								(size 1.27 1.27)
							)
						)
					)
				)
				(pin input line
					(at 0 -5.08 0)
					(length 2.54)
					(name "EN"
						(effects
							(font
								(size 1.27 1.27)
							)
						)
					)
					(number "5"
						(effects
							(font
								(size 1.27 1.27)
							)
						)
					)
				)
				(pin output line
					(at 20.32 -5.08 180)
					(length 2.54)
					(name "BST"
						(effects
							(font
								(size 1.27 1.27)
							)
						)
					)
					(number "6"
						(effects
							(font
								(size 1.27 1.27)
							)
						)
					)
				)
			)
		)
	(symbol "antmicroFCCConnectors:Conn_FFC_WE_68715014022"
			(exclude_from_sim no)
			(in_bom yes)
			(on_board yes)
			(property "Reference" "J"
				(at 19.05 -5.08 0)
				(effects
					(font
						(size 1.27 1.27)
						(thickness 0.15)
					)
					(justify left bottom)
				)
			)
			(property "Value" "Conn_FFC_WE_68715014022"
				(at 19.05 -7.62 0)
				(effects
					(font
						(size 1.27 1.27)
						(thickness 0.15)
					)
					(justify left bottom)
					(hide yes)
				)
			)
			(property "Footprint" "antmicro-footprints:Conn_FFC_WE_68715014x22"
				(at 19.05 -10.16 0)
				(effects
					(font
						(size 1.27 1.27)
						(thickness 0.15)
					)
					(justify left bottom)
					(hide yes)
				)
			)
			(property "Datasheet" "https://www.we-online.com/components/products/datasheet/68715014022.pdf"
				(at 19.05 -12.7 0)
				(effects
					(font
						(size 1.27 1.27)
						(thickness 0.15)
					)
					(justify left bottom)
					(hide yes)
				)
			)
			(property "Description" "FFC connector"
				(at 0 0 0)
				(effects
					(font
						(size 1.27 1.27)
					)
					(hide yes)
				)
			)
			(property "MPN" "68715014022"
				(at 19.05 -15.24 0)
				(effects
					(font
						(size 1.27 1.27)
						(thickness 0.15)
					)
					(justify left bottom)
				)
			)
			(property "Manufacturer" "Würth Elektronik"
				(at 19.05 -17.78 0)
				(effects
					(font
						(size 1.27 1.27)
						(thickness 0.15)
					)
					(justify left bottom)
					(hide yes)
				)
			)
			(property "Author" "Antmicro"
				(at 19.05 -20.32 0)
				(effects
					(font
						(size 1.27 1.27)
						(thickness 0.15)
					)
					(justify left bottom)
					(hide yes)
				)
			)
			(property "License" "Apache-2.0"
				(at 19.05 -22.86 0)
				(effects
					(font
						(size 1.27 1.27)
						(thickness 0.15)
					)
					(justify left bottom)
					(hide yes)
				)
			)
			(property "ki_keywords" "CONNECTOR"
				(at 0 0 0)
				(effects
					(font
						(size 1.27 1.27)
					)
					(hide yes)
				)
			)
			(symbol "Conn_FFC_WE_68715014022_1_1"
				(rectangle
					(start 3.81 -124.333)
					(end 5.08 -124.587)
					(stroke
						(width 0.254)
						(type default)
					)
					(fill
						(type background)
					)
				)
				(rectangle
					(start 3.81 -121.793)
					(end 5.08 -122.047)
					(stroke
						(width 0.254)
						(type default)
					)
					(fill
						(type background)
					)
				)
				(rectangle
					(start 3.81 -119.253)
					(end 5.08 -119.507)
					(stroke
						(width 0.254)
						(type default)
					)
					(fill
						(type background)
					)
				)
				(rectangle
					(start 3.81 -116.713)
					(end 5.08 -116.967)
					(stroke
						(width 0.254)
						(type default)
					)
					(fill
						(type background)
					)
				)
				(rectangle
					(start 3.81 -114.173)
					(end 5.08 -114.427)
					(stroke
						(width 0.254)
						(type default)
					)
					(fill
						(type background)
					)
				)
				(rectangle
					(start 3.81 -111.633)
					(end 5.08 -111.887)
					(stroke
						(width 0.254)
						(type default)
					)
					(fill
						(type background)
					)
				)
				(rectangle
					(start 3.81 -109.093)
					(end 5.08 -109.347)
					(stroke
						(width 0.254)
						(type default)
					)
					(fill
						(type background)
					)
				)
				(rectangle
					(start 3.81 -106.553)
					(end 5.08 -106.807)
					(stroke
						(width 0.254)
						(type default)
					)
					(fill
						(type background)
					)
				)
				(rectangle
					(start 3.81 -104.013)
					(end 5.08 -104.267)
					(stroke
						(width 0.254)
						(type default)
					)
					(fill
						(type background)
					)
				)
				(rectangle
					(start 3.81 -101.473)
					(end 5.08 -101.727)
					(stroke
						(width 0.254)
						(type default)
					)
					(fill
						(type background)
					)
				)
				(rectangle
					(start 3.81 -98.933)
					(end 5.08 -99.187)
					(stroke
						(width 0.254)
						(type default)
					)
					(fill
						(type background)
					)
				)
				(rectangle
					(start 3.81 -96.393)
					(end 5.08 -96.647)
					(stroke
						(width 0.254)
						(type default)
					)
					(fill
						(type background)
					)
				)
				(rectangle
					(start 3.81 -93.853)
					(end 5.08 -94.107)
					(stroke
						(width 0.254)
						(type default)
					)
					(fill
						(type background)
					)
				)
				(rectangle
					(start 3.81 -91.313)
					(end 5.08 -91.567)
					(stroke
						(width 0.254)
						(type default)
					)
					(fill
						(type background)
					)
				)
				(rectangle
					(start 3.81 -88.773)
					(end 5.08 -89.027)
					(stroke
						(width 0.254)
						(type default)
					)
					(fill
						(type background)
					)
				)
				(rectangle
					(start 3.81 -86.233)
					(end 5.08 -86.487)
					(stroke
						(width 0.254)
						(type default)
					)
					(fill
						(type background)
					)
				)
				(rectangle
					(start 3.81 -83.693)
					(end 5.08 -83.947)
					(stroke
						(width 0.254)
						(type default)
					)
					(fill
						(type background)
					)
				)
				(rectangle
					(start 3.81 -81.153)
					(end 5.08 -81.407)
					(stroke
						(width 0.254)
						(type default)
					)
					(fill
						(type background)
					)
				)
				(rectangle
					(start 3.81 -78.613)
					(end 5.08 -78.867)
					(stroke
						(width 0.254)
						(type default)
					)
					(fill
						(type background)
					)
				)
				(rectangle
					(start 3.81 -76.073)
					(end 5.08 -76.327)
					(stroke
						(width 0.254)
						(type default)
					)
					(fill
						(type background)
					)
				)
				(rectangle
					(start 3.81 -73.533)
					(end 5.08 -73.787)
					(stroke
						(width 0.254)
						(type default)
					)
					(fill
						(type background)
					)
				)
				(rectangle
					(start 3.81 -70.993)
					(end 5.08 -71.247)
					(stroke
						(width 0.254)
						(type default)
					)
					(fill
						(type background)
					)
				)
				(rectangle
					(start 3.81 -68.453)
					(end 5.08 -68.707)
					(stroke
						(width 0.254)
						(type default)
					)
					(fill
						(type background)
					)
				)
				(rectangle
					(start 3.81 -65.913)
					(end 5.08 -66.167)
					(stroke
						(width 0.254)
						(type default)
					)
					(fill
						(type background)
					)
				)
				(rectangle
					(start 3.81 -63.373)
					(end 5.08 -63.627)
					(stroke
						(width 0.254)
						(type default)
					)
					(fill
						(type background)
					)
				)
				(rectangle
					(start 3.81 -60.833)
					(end 5.08 -61.087)
					(stroke
						(width 0.254)
						(type default)
					)
					(fill
						(type background)
					)
				)
				(rectangle
					(start 3.81 -58.293)
					(end 5.08 -58.547)
					(stroke
						(width 0.254)
						(type default)
					)
					(fill
						(type background)
					)
				)
				(rectangle
					(start 3.81 -55.753)
					(end 5.08 -56.007)
					(stroke
						(width 0.254)
						(type default)
					)
					(fill
						(type background)
					)
				)
				(rectangle
					(start 3.81 -53.213)
					(end 5.08 -53.467)
					(stroke
						(width 0.254)
						(type default)
					)
					(fill
						(type background)
					)
				)
				(rectangle
					(start 3.81 -50.673)
					(end 5.08 -50.927)
					(stroke
						(width 0.254)
						(type default)
					)
					(fill
						(type background)
					)
				)
				(rectangle
					(start 3.81 -48.133)
					(end 5.08 -48.387)
					(stroke
						(width 0.254)
						(type default)
					)
					(fill
						(type background)
					)
				)
				(rectangle
					(start 3.81 -45.593)
					(end 5.08 -45.847)
					(stroke
						(width 0.254)
						(type default)
					)
					(fill
						(type background)
					)
				)
				(rectangle
					(start 3.81 -43.053)
					(end 5.08 -43.307)
					(stroke
						(width 0.254)
						(type default)
					)
					(fill
						(type background)
					)
				)
				(rectangle
					(start 3.81 -40.513)
					(end 5.08 -40.767)
					(stroke
						(width 0.254)
						(type default)
					)
					(fill
						(type background)
					)
				)
				(rectangle
					(start 3.81 -37.973)
					(end 5.08 -38.227)
					(stroke
						(width 0.254)
						(type default)
					)
					(fill
						(type background)
					)
				)
				(rectangle
					(start 3.81 -35.433)
					(end 5.08 -35.687)
					(stroke
						(width 0.254)
						(type default)
					)
					(fill
						(type background)
					)
				)
				(rectangle
					(start 3.81 -32.893)
					(end 5.08 -33.147)
					(stroke
						(width 0.254)
						(type default)
					)
					(fill
						(type background)
					)
				)
				(rectangle
					(start 3.81 -30.353)
					(end 5.08 -30.607)
					(stroke
						(width 0.254)
						(type default)
					)
					(fill
						(type background)
					)
				)
				(rectangle
					(start 3.81 -27.813)
					(end 5.08 -28.067)
					(stroke
						(width 0.254)
						(type default)
					)
					(fill
						(type background)
					)
				)
				(rectangle
					(start 3.81 -25.273)
					(end 5.08 -25.527)
					(stroke
						(width 0.254)
						(type default)
					)
					(fill
						(type background)
					)
				)
				(rectangle
					(start 3.81 -22.733)
					(end 5.08 -22.987)
					(stroke
						(width 0.254)
						(type default)
					)
					(fill
						(type background)
					)
				)
				(rectangle
					(start 3.81 -20.193)
					(end 5.08 -20.447)
					(stroke
						(width 0.254)
						(type default)
					)
					(fill
						(type background)
					)
				)
				(rectangle
					(start 3.81 -17.653)
					(end 5.08 -17.907)
					(stroke
						(width 0.254)
						(type default)
					)
					(fill
						(type background)
					)
				)
				(rectangle
					(start 3.81 -15.113)
					(end 5.08 -15.367)
					(stroke
						(width 0.254)
						(type default)
					)
					(fill
						(type background)
					)
				)
				(rectangle
					(start 3.81 -12.573)
					(end 5.08 -12.827)
					(stroke
						(width 0.254)
						(type default)
					)
					(fill
						(type background)
					)
				)
				(rectangle
					(start 3.81 -10.033)
					(end 5.08 -10.287)
					(stroke
						(width 0.254)
						(type default)
					)
					(fill
						(type background)
					)
				)
				(rectangle
					(start 3.81 -7.493)
					(end 5.08 -7.747)
					(stroke
						(width 0.254)
						(type default)
					)
					(fill
						(type background)
					)
				)
				(rectangle
					(start 3.81 -4.953)
					(end 5.08 -5.207)
					(stroke
						(width 0.254)
						(type default)
					)
					(fill
						(type background)
					)
				)
				(rectangle
					(start 3.81 -2.413)
					(end 5.08 -2.667)
					(stroke
						(width 0.254)
						(type default)
					)
					(fill
						(type background)
					)
				)
				(rectangle
					(start 3.81 0.127)
					(end 5.08 -0.127)
					(stroke
						(width 0.254)
						(type default)
					)
					(fill
						(type background)
					)
				)
				(rectangle
					(start 3.81 1.27)
					(end 7.62 -132.08)
					(stroke
						(width 0.254)
						(type default)
					)
					(fill
						(type background)
					)
				)
				(pin passive line
					(at 0 0 0)
					(length 3.81)
					(name "~"
						(effects
							(font
								(size 1.27 1.27)
							)
						)
					)
					(number "1"
						(effects
							(font
								(size 1.27 1.27)
							)
						)
					)
				)
				(pin passive line
					(at 0 -22.86 0)
					(length 3.81)
					(name "~"
						(effects
							(font
								(size 1.27 1.27)
							)
						)
					)
					(number "10"
						(effects
							(font
								(size 1.27 1.27)
							)
						)
					)
				)
				(pin passive line
					(at 0 -25.4 0)
					(length 3.81)
					(name "~"
						(effects
							(font
								(size 1.27 1.27)
							)
						)
					)
					(number "11"
						(effects
							(font
								(size 1.27 1.27)
							)
						)
					)
				)
				(pin passive line
					(at 0 -27.94 0)
					(length 3.81)
					(name "~"
						(effects
							(font
								(size 1.27 1.27)
							)
						)
					)
					(number "12"
						(effects
							(font
								(size 1.27 1.27)
							)
						)
					)
				)
				(pin passive line
					(at 0 -30.48 0)
					(length 3.81)
					(name "~"
						(effects
							(font
								(size 1.27 1.27)
							)
						)
					)
					(number "13"
						(effects
							(font
								(size 1.27 1.27)
							)
						)
					)
				)
				(pin passive line
					(at 0 -33.02 0)
					(length 3.81)
					(name "~"
						(effects
							(font
								(size 1.27 1.27)
							)
						)
					)
					(number "14"
						(effects
							(font
								(size 1.27 1.27)
							)
						)
					)
				)
				(pin passive line
					(at 0 -35.56 0)
					(length 3.81)
					(name "~"
						(effects
							(font
								(size 1.27 1.27)
							)
						)
					)
					(number "15"
						(effects
							(font
								(size 1.27 1.27)
							)
						)
					)
				)
				(pin passive line
					(at 0 -38.1 0)
					(length 3.81)
					(name "~"
						(effects
							(font
								(size 1.27 1.27)
							)
						)
					)
					(number "16"
						(effects
							(font
								(size 1.27 1.27)
							)
						)
					)
				)
				(pin passive line
					(at 0 -40.64 0)
					(length 3.81)
					(name "~"
						(effects
							(font
								(size 1.27 1.27)
							)
						)
					)
					(number "17"
						(effects
							(font
								(size 1.27 1.27)
							)
						)
					)
				)
				(pin passive line
					(at 0 -43.18 0)
					(length 3.81)
					(name "~"
						(effects
							(font
								(size 1.27 1.27)
							)
						)
					)
					(number "18"
						(effects
							(font
								(size 1.27 1.27)
							)
						)
					)
				)
				(pin passive line
					(at 0 -45.72 0)
					(length 3.81)
					(name "~"
						(effects
							(font
								(size 1.27 1.27)
							)
						)
					)
					(number "19"
						(effects
							(font
								(size 1.27 1.27)
							)
						)
					)
				)
				(pin passive line
					(at 0 -2.54 0)
					(length 3.81)
					(name "~"
						(effects
							(font
								(size 1.27 1.27)
							)
						)
					)
					(number "2"
						(effects
							(font
								(size 1.27 1.27)
							)
						)
					)
				)
				(pin passive line
					(at 0 -48.26 0)
					(length 3.81)
					(name "~"
						(effects
							(font
								(size 1.27 1.27)
							)
						)
					)
					(number "20"
						(effects
							(font
								(size 1.27 1.27)
							)
						)
					)
				)
				(pin passive line
					(at 0 -50.8 0)
					(length 3.81)
					(name "~"
						(effects
							(font
								(size 1.27 1.27)
							)
						)
					)
					(number "21"
						(effects
							(font
								(size 1.27 1.27)
							)
						)
					)
				)
				(pin passive line
					(at 0 -53.34 0)
					(length 3.81)
					(name "~"
						(effects
							(font
								(size 1.27 1.27)
							)
						)
					)
					(number "22"
						(effects
							(font
								(size 1.27 1.27)
							)
						)
					)
				)
				(pin passive line
					(at 0 -55.88 0)
					(length 3.81)
					(name "~"
						(effects
							(font
								(size 1.27 1.27)
							)
						)
					)
					(number "23"
						(effects
							(font
								(size 1.27 1.27)
							)
						)
					)
				)
				(pin passive line
					(at 0 -58.42 0)
					(length 3.81)
					(name "~"
						(effects
							(font
								(size 1.27 1.27)
							)
						)
					)
					(number "24"
						(effects
							(font
								(size 1.27 1.27)
							)
						)
					)
				)
				(pin passive line
					(at 0 -60.96 0)
					(length 3.81)
					(name "~"
						(effects
							(font
								(size 1.27 1.27)
							)
						)
					)
					(number "25"
						(effects
							(font
								(size 1.27 1.27)
							)
						)
					)
				)
				(pin passive line
					(at 0 -63.5 0)
					(length 3.81)
					(name "~"
						(effects
							(font
								(size 1.27 1.27)
							)
						)
					)
					(number "26"
						(effects
							(font
								(size 1.27 1.27)
							)
						)
					)
				)
				(pin passive line
					(at 0 -66.04 0)
					(length 3.81)
					(name "~"
						(effects
							(font
								(size 1.27 1.27)
							)
						)
					)
					(number "27"
						(effects
							(font
								(size 1.27 1.27)
							)
						)
					)
				)
				(pin passive line
					(at 0 -68.58 0)
					(length 3.81)
					(name "~"
						(effects
							(font
								(size 1.27 1.27)
							)
						)
					)
					(number "28"
						(effects
							(font
								(size 1.27 1.27)
							)
						)
					)
				)
				(pin passive line
					(at 0 -71.12 0)
					(length 3.81)
					(name "~"
						(effects
							(font
								(size 1.27 1.27)
							)
						)
					)
					(number "29"
						(effects
							(font
								(size 1.27 1.27)
							)
						)
					)
				)
				(pin passive line
					(at 0 -5.08 0)
					(length 3.81)
					(name "~"
						(effects
							(font
								(size 1.27 1.27)
							)
						)
					)
					(number "3"
						(effects
							(font
								(size 1.27 1.27)
							)
						)
					)
				)
				(pin passive line
					(at 0 -73.66 0)
					(length 3.81)
					(name "~"
						(effects
							(font
								(size 1.27 1.27)
							)
						)
					)
					(number "30"
						(effects
							(font
								(size 1.27 1.27)
							)
						)
					)
				)
				(pin passive line
					(at 0 -76.2 0)
					(length 3.81)
					(name "~"
						(effects
							(font
								(size 1.27 1.27)
							)
						)
					)
					(number "31"
						(effects
							(font
								(size 1.27 1.27)
							)
						)
					)
				)
				(pin passive line
					(at 0 -78.74 0)
					(length 3.81)
					(name "~"
						(effects
							(font
								(size 1.27 1.27)
							)
						)
					)
					(number "32"
						(effects
							(font
								(size 1.27 1.27)
							)
						)
					)
				)
				(pin passive line
					(at 0 -81.28 0)
					(length 3.81)
					(name "~"
						(effects
							(font
								(size 1.27 1.27)
							)
						)
					)
					(number "33"
						(effects
							(font
								(size 1.27 1.27)
							)
						)
					)
				)
				(pin passive line
					(at 0 -83.82 0)
					(length 3.81)
					(name "~"
						(effects
							(font
								(size 1.27 1.27)
							)
						)
					)
					(number "34"
						(effects
							(font
								(size 1.27 1.27)
							)
						)
					)
				)
				(pin passive line
					(at 0 -86.36 0)
					(length 3.81)
					(name "~"
						(effects
							(font
								(size 1.27 1.27)
							)
						)
					)
					(number "35"
						(effects
							(font
								(size 1.27 1.27)
							)
						)
					)
				)
				(pin passive line
					(at 0 -88.9 0)
					(length 3.81)
					(name "~"
						(effects
							(font
								(size 1.27 1.27)
							)
						)
					)
					(number "36"
						(effects
							(font
								(size 1.27 1.27)
							)
						)
					)
				)
				(pin passive line
					(at 0 -91.44 0)
					(length 3.81)
					(name "~"
						(effects
							(font
								(size 1.27 1.27)
							)
						)
					)
					(number "37"
						(effects
							(font
								(size 1.27 1.27)
							)
						)
					)
				)
				(pin passive line
					(at 0 -93.98 0)
					(length 3.81)
					(name "~"
						(effects
							(font
								(size 1.27 1.27)
							)
						)
					)
					(number "38"
						(effects
							(font
								(size 1.27 1.27)
							)
						)
					)
				)
				(pin passive line
					(at 0 -96.52 0)
					(length 3.81)
					(name "~"
						(effects
							(font
								(size 1.27 1.27)
							)
						)
					)
					(number "39"
						(effects
							(font
								(size 1.27 1.27)
							)
						)
					)
				)
				(pin passive line
					(at 0 -7.62 0)
					(length 3.81)
					(name "~"
						(effects
							(font
								(size 1.27 1.27)
							)
						)
					)
					(number "4"
						(effects
							(font
								(size 1.27 1.27)
							)
						)
					)
				)
				(pin passive line
					(at 0 -99.06 0)
					(length 3.81)
					(name "~"
						(effects
							(font
								(size 1.27 1.27)
							)
						)
					)
					(number "40"
						(effects
							(font
								(size 1.27 1.27)
							)
						)
					)
				)
				(pin passive line
					(at 0 -101.6 0)
					(length 3.81)
					(name "~"
						(effects
							(font
								(size 1.27 1.27)
							)
						)
					)
					(number "41"
						(effects
							(font
								(size 1.27 1.27)
							)
						)
					)
				)
				(pin passive line
					(at 0 -104.14 0)
					(length 3.81)
					(name "~"
						(effects
							(font
								(size 1.27 1.27)
							)
						)
					)
					(number "42"
						(effects
							(font
								(size 1.27 1.27)
							)
						)
					)
				)
				(pin passive line
					(at 0 -106.68 0)
					(length 3.81)
					(name "~"
						(effects
							(font
								(size 1.27 1.27)
							)
						)
					)
					(number "43"
						(effects
							(font
								(size 1.27 1.27)
							)
						)
					)
				)
				(pin passive line
					(at 0 -109.22 0)
					(length 3.81)
					(name "~"
						(effects
							(font
								(size 1.27 1.27)
							)
						)
					)
					(number "44"
						(effects
							(font
								(size 1.27 1.27)
							)
						)
					)
				)
				(pin passive line
					(at 0 -111.76 0)
					(length 3.81)
					(name "~"
						(effects
							(font
								(size 1.27 1.27)
							)
						)
					)
					(number "45"
						(effects
							(font
								(size 1.27 1.27)
							)
						)
					)
				)
				(pin passive line
					(at 0 -114.3 0)
					(length 3.81)
					(name "~"
						(effects
							(font
								(size 1.27 1.27)
							)
						)
					)
					(number "46"
						(effects
							(font
								(size 1.27 1.27)
							)
						)
					)
				)
				(pin passive line
					(at 0 -116.84 0)
					(length 3.81)
					(name "~"
						(effects
							(font
								(size 1.27 1.27)
							)
						)
					)
					(number "47"
						(effects
							(font
								(size 1.27 1.27)
							)
						)
					)
				)
				(pin passive line
					(at 0 -119.38 0)
					(length 3.81)
					(name "~"
						(effects
							(font
								(size 1.27 1.27)
							)
						)
					)
					(number "48"
						(effects
							(font
								(size 1.27 1.27)
							)
						)
					)
				)
				(pin passive line
					(at 0 -121.92 0)
					(length 3.81)
					(name "~"
						(effects
							(font
								(size 1.27 1.27)
							)
						)
					)
					(number "49"
						(effects
							(font
								(size 1.27 1.27)
							)
						)
					)
				)
				(pin passive line
					(at 0 -10.16 0)
					(length 3.81)
					(name "~"
						(effects
							(font
								(size 1.27 1.27)
							)
						)
					)
					(number "5"
						(effects
							(font
								(size 1.27 1.27)
							)
						)
					)
				)
				(pin passive line
					(at 0 -124.46 0)
					(length 3.81)
					(name "~"
						(effects
							(font
								(size 1.27 1.27)
							)
						)
					)
					(number "50"
						(effects
							(font
								(size 1.27 1.27)
							)
						)
					)
				)
				(pin passive line
					(at 0 -12.7 0)
					(length 3.81)
					(name "~"
						(effects
							(font
								(size 1.27 1.27)
							)
						)
					)
					(number "6"
						(effects
							(font
								(size 1.27 1.27)
							)
						)
					)
				)
				(pin passive line
					(at 0 -15.24 0)
					(length 3.81)
					(name "~"
						(effects
							(font
								(size 1.27 1.27)
							)
						)
					)
					(number "7"
						(effects
							(font
								(size 1.27 1.27)
							)
						)
					)
				)
				(pin passive line
					(at 0 -17.78 0)
					(length 3.81)
					(name "~"
						(effects
							(font
								(size 1.27 1.27)
							)
						)
					)
					(number "8"
						(effects
							(font
								(size 1.27 1.27)
							)
						)
					)
				)
				(pin passive line
					(at 0 -20.32 0)
					(length 3.81)
					(name "~"
						(effects
							(font
								(size 1.27 1.27)
							)
						)
					)
					(number "9"
						(effects
							(font
								(size 1.27 1.27)
							)
						)
					)
				)
				(pin passive line
					(at 0 -127 0)
					(length 3.81)
					(name "MP"
						(effects
							(font
								(size 1.27 1.27)
							)
						)
					)
					(number "MP1"
						(effects
							(font
								(size 1.27 1.27)
							)
						)
					)
				)
				(pin passive line
					(at 0 -129.54 0)
					(length 3.81)
					(name "MP"
						(effects
							(font
								(size 1.27 1.27)
							)
						)
					)
					(number "MP2"
						(effects
							(font
								(size 1.27 1.27)
							)
						)
					)
				)
			)
		)
	(symbol "antmicroFixedInductors:L_1u_2.6A_0806"
			(pin_numbers hide)
			(pin_names hide)
			(exclude_from_sim no)
			(in_bom yes)
			(on_board yes)
			(property "Reference" "L"
				(at 13.97 0 0)
				(effects
					(font
						(size 1.27 1.27)
						(thickness 0.15)
					)
					(justify left bottom)
				)
			)
			(property "Value" "L_1u_2.6A_0806"
				(at 13.97 -2.54 0)
				(effects
					(font
						(size 1.27 1.27)
						(thickness 0.15)
					)
					(justify left bottom)
					(hide yes)
				)
			)
			(property "Footprint" "antmicro-footprints:L_0806_2016Metric"
				(at 13.97 -7.62 0)
				(effects
					(font
						(size 1.27 1.27)
						(thickness 0.15)
					)
					(justify left bottom)
					(hide yes)
				)
			)
			(property "Datasheet" "https://www.bourns.com/docs/Product-Datasheets/SRP2010.pdf"
				(at 13.97 -10.16 0)
				(effects
					(font
						(size 1.27 1.27)
						(thickness 0.15)
					)
					(justify left bottom)
					(hide yes)
				)
			)
			(property "Description" "Wirewound Inductor, 1 µH, 0.072 ohm, 2.6 A, SRP2010"
				(at 0 0 0)
				(effects
					(font
						(size 1.27 1.27)
					)
					(hide yes)
				)
			)
			(property "Val" "1u/2.6A"
				(at 13.97 -5.08 0)
				(effects
					(font
						(size 1.27 1.27)
						(thickness 0.15)
					)
					(justify left bottom)
				)
			)
			(property "Manufacturer" "Bourns"
				(at 13.97 -12.7 0)
				(effects
					(font
						(size 1.27 1.27)
						(thickness 0.15)
					)
					(justify left bottom)
					(hide yes)
				)
			)
			(property "MPN" "SRP2010-1R0M"
				(at 13.97 -15.24 0)
				(effects
					(font
						(size 1.27 1.27)
						(thickness 0.15)
					)
					(justify left bottom)
					(hide yes)
				)
			)
			(property "ISat" "2.9 A"
				(at 13.97 -16.51 0)
				(effects
					(font
						(size 1.27 1.27)
					)
					(justify left)
					(hide yes)
				)
			)
			(property "IMax" "2.6 A"
				(at 13.97 -20.32 0)
				(effects
					(font
						(size 1.27 1.27)
						(thickness 0.15)
					)
					(justify left bottom)
					(hide yes)
				)
			)
			(property "Size" "2.0x1.6"
				(at 13.97 -22.86 0)
				(effects
					(font
						(size 1.27 1.27)
						(thickness 0.15)
					)
					(justify left bottom)
					(hide yes)
				)
			)
			(property "Author" "Antmicro"
				(at 13.97 -25.4 0)
				(effects
					(font
						(size 1.27 1.27)
						(thickness 0.15)
					)
					(justify left bottom)
					(hide yes)
				)
			)
			(property "License" "Apache-2.0"
				(at 13.97 -27.94 0)
				(effects
					(font
						(size 1.27 1.27)
						(thickness 0.15)
					)
					(justify left bottom)
					(hide yes)
				)
			)
			(property "ki_keywords" "SMT, INDUCTOR, PASSIVE"
				(at 0 0 0)
				(effects
					(font
						(size 1.27 1.27)
					)
					(hide yes)
				)
			)
			(symbol "L_1u_2.6A_0806_0_1"
				(arc
					(start 1.524 0)
					(mid 1.016 0.5058)
					(end 0.508 0)
					(stroke
						(width 0)
						(type default)
					)
					(fill
						(type none)
					)
				)
				(arc
					(start 2.54 0)
					(mid 2.032 0.5058)
					(end 1.524 0)
					(stroke
						(width 0)
						(type default)
					)
					(fill
						(type none)
					)
				)
				(arc
					(start 3.556 0)
					(mid 3.048 0.5058)
					(end 2.54 0)
					(stroke
						(width 0)
						(type default)
					)
					(fill
						(type none)
					)
				)
				(arc
					(start 4.572 0)
					(mid 4.064 0.5058)
					(end 3.556 0)
					(stroke
						(width 0)
						(type default)
					)
					(fill
						(type none)
					)
				)
			)
			(symbol "L_1u_2.6A_0806_1_1"
				(pin passive line
					(at 0 0 0)
					(length 0.508)
					(name "~"
						(effects
							(font
								(size 1.27 1.27)
							)
						)
					)
					(number "1"
						(effects
							(font
								(size 1.27 1.27)
							)
						)
					)
				)
				(pin passive line
					(at 5.08 0 180)
					(length 0.508)
					(name "~"
						(effects
							(font
								(size 1.27 1.27)
							)
						)
					)
					(number "2"
						(effects
							(font
								(size 1.27 1.27)
							)
						)
					)
				)
			)
		)
	(symbol "antmicroFixedInductors:L_22u_1.12A_Coilcraft-MSS6132T"
			(pin_numbers hide)
			(pin_names hide)
			(exclude_from_sim no)
			(in_bom yes)
			(on_board yes)
			(property "Reference" "L"
				(at 13.97 0 0)
				(effects
					(font
						(size 1.27 1.27)
						(thickness 0.15)
					)
					(justify left bottom)
				)
			)
			(property "Value" "L_22u_1.12A_Coilcraft-MSS6132T"
				(at 13.97 -2.54 0)
				(effects
					(font
						(size 1.27 1.27)
						(thickness 0.15)
					)
					(justify left bottom)
					(hide yes)
				)
			)
			(property "Footprint" "antmicro-footprints:L_Coilcraft-MSS6132T"
				(at 13.97 -7.62 0)
				(effects
					(font
						(size 1.27 1.27)
						(thickness 0.15)
					)
					(justify left bottom)
					(hide yes)
				)
			)
			(property "Datasheet" "https://www.coilcraft.com/getmedia/d035c9b3-191d-46aa-ab3f-5c1a849157c1/mss6132t.pdf"
				(at 13.97 -10.16 0)
				(effects
					(font
						(size 1.27 1.27)
						(thickness 0.15)
					)
					(justify left bottom)
					(hide yes)
				)
			)
			(property "Description" "Power Inductor (SMT), 22 µH, 1.85 A, Shielded, 2.45 A, WE-MAPI"
				(at 0 0 0)
				(effects
					(font
						(size 1.27 1.27)
					)
					(hide yes)
				)
			)
			(property "Val" "22u/1.12A"
				(at 13.97 -5.08 0)
				(effects
					(font
						(size 1.27 1.27)
						(thickness 0.15)
					)
					(justify left bottom)
				)
			)
			(property "Manufacturer" "Coilcraft"
				(at 13.97 -12.7 0)
				(effects
					(font
						(size 1.27 1.27)
						(thickness 0.15)
					)
					(justify left bottom)
					(hide yes)
				)
			)
			(property "MPN" "MSS6132T-223"
				(at 13.97 -15.24 0)
				(effects
					(font
						(size 1.27 1.27)
						(thickness 0.15)
					)
					(justify left bottom)
					(hide yes)
				)
			)
			(property "ISat" "1.12A"
				(at 13.97 -16.51 0)
				(effects
					(font
						(size 1.27 1.27)
					)
					(justify left)
					(hide yes)
				)
			)
			(property "IMax" "1.45A"
				(at 13.97 -20.32 0)
				(effects
					(font
						(size 1.27 1.27)
						(thickness 0.15)
					)
					(justify left bottom)
					(hide yes)
				)
			)
			(property "Size" "6.1x6.1"
				(at 13.97 -22.86 0)
				(effects
					(font
						(size 1.27 1.27)
						(thickness 0.15)
					)
					(justify left bottom)
					(hide yes)
				)
			)
			(property "Author" "Antmicro"
				(at 13.97 -25.4 0)
				(effects
					(font
						(size 1.27 1.27)
						(thickness 0.15)
					)
					(justify left bottom)
					(hide yes)
				)
			)
			(property "License" "Apache-2.0"
				(at 13.97 -27.94 0)
				(effects
					(font
						(size 1.27 1.27)
						(thickness 0.15)
					)
					(justify left bottom)
					(hide yes)
				)
			)
			(property "ki_keywords" "SMT, INDUCTOR, PASSIVE"
				(at 0 0 0)
				(effects
					(font
						(size 1.27 1.27)
					)
					(hide yes)
				)
			)
			(symbol "L_22u_1.12A_Coilcraft-MSS6132T_0_1"
				(arc
					(start 1.524 0)
					(mid 1.016 0.5058)
					(end 0.508 0)
					(stroke
						(width 0)
						(type default)
					)
					(fill
						(type none)
					)
				)
				(arc
					(start 2.54 0)
					(mid 2.032 0.5058)
					(end 1.524 0)
					(stroke
						(width 0)
						(type default)
					)
					(fill
						(type none)
					)
				)
				(arc
					(start 3.556 0)
					(mid 3.048 0.5058)
					(end 2.54 0)
					(stroke
						(width 0)
						(type default)
					)
					(fill
						(type none)
					)
				)
				(arc
					(start 4.572 0)
					(mid 4.064 0.5058)
					(end 3.556 0)
					(stroke
						(width 0)
						(type default)
					)
					(fill
						(type none)
					)
				)
			)
			(symbol "L_22u_1.12A_Coilcraft-MSS6132T_1_1"
				(pin passive line
					(at 0 0 0)
					(length 0.508)
					(name "~"
						(effects
							(font
								(size 1.27 1.27)
							)
						)
					)
					(number "1"
						(effects
							(font
								(size 1.27 1.27)
							)
						)
					)
				)
				(pin passive line
					(at 5.08 0 180)
					(length 0.508)
					(name "~"
						(effects
							(font
								(size 1.27 1.27)
							)
						)
					)
					(number "2"
						(effects
							(font
								(size 1.27 1.27)
							)
						)
					)
				)
			)
		)
	(symbol "antmicroFixedInductors:L_3u3_3.1A_Bourns-SRP3212A"
			(pin_numbers hide)
			(pin_names hide)
			(exclude_from_sim no)
			(in_bom yes)
			(on_board yes)
			(property "Reference" "L"
				(at 13.97 0 0)
				(effects
					(font
						(size 1.27 1.27)
						(thickness 0.15)
					)
					(justify left bottom)
				)
			)
			(property "Value" "L_3u3_3.1A_Bourns-SRP3212A"
				(at 13.97 -2.54 0)
				(effects
					(font
						(size 1.27 1.27)
						(thickness 0.15)
					)
					(justify left bottom)
					(hide yes)
				)
			)
			(property "Footprint" "antmicro-footprints:L_Bourns-SRP3212A"
				(at 13.97 -7.62 0)
				(effects
					(font
						(size 1.27 1.27)
						(thickness 0.15)
					)
					(justify left bottom)
					(hide yes)
				)
			)
			(property "Datasheet" "https://www.mouser.com/datasheet/2/54/SRP3212A-3011944.pdf"
				(at 13.97 -10.16 0)
				(effects
					(font
						(size 1.27 1.27)
						(thickness 0.15)
					)
					(justify left bottom)
					(hide yes)
				)
			)
			(property "Description" "Power Inductor (SMD), 3.3 µH, 3.1 A, Shielded, 3.4 A, SRP3212 Series"
				(at 0 0 0)
				(effects
					(font
						(size 1.27 1.27)
					)
					(hide yes)
				)
			)
			(property "Val" "3u3/3.1A"
				(at 13.97 -5.08 0)
				(effects
					(font
						(size 1.27 1.27)
						(thickness 0.15)
					)
					(justify left bottom)
				)
			)
			(property "Manufacturer" "Bourns"
				(at 13.97 -12.7 0)
				(effects
					(font
						(size 1.27 1.27)
						(thickness 0.15)
					)
					(justify left bottom)
					(hide yes)
				)
			)
			(property "MPN" "SRP3212-3R3M"
				(at 13.97 -15.24 0)
				(effects
					(font
						(size 1.27 1.27)
						(thickness 0.15)
					)
					(justify left bottom)
					(hide yes)
				)
			)
			(property "ISat" "3.4 A"
				(at 13.97 -16.51 0)
				(effects
					(font
						(size 1.27 1.27)
					)
					(justify left)
					(hide yes)
				)
			)
			(property "IMax" "3.1 A"
				(at 13.97 -20.32 0)
				(effects
					(font
						(size 1.27 1.27)
						(thickness 0.15)
					)
					(justify left bottom)
					(hide yes)
				)
			)
			(property "Size" "3.2x2.5"
				(at 13.97 -22.86 0)
				(effects
					(font
						(size 1.27 1.27)
						(thickness 0.15)
					)
					(justify left bottom)
					(hide yes)
				)
			)
			(property "Author" "Antmicro"
				(at 13.97 -25.4 0)
				(effects
					(font
						(size 1.27 1.27)
						(thickness 0.15)
					)
					(justify left bottom)
					(hide yes)
				)
			)
			(property "License" "Apache-2.0"
				(at 13.97 -27.94 0)
				(effects
					(font
						(size 1.27 1.27)
						(thickness 0.15)
					)
					(justify left bottom)
					(hide yes)
				)
			)
			(property "ki_keywords" "SMT, INDUCTOR, PASSIVE"
				(at 0 0 0)
				(effects
					(font
						(size 1.27 1.27)
					)
					(hide yes)
				)
			)
			(symbol "L_3u3_3.1A_Bourns-SRP3212A_0_1"
				(arc
					(start 1.524 0)
					(mid 1.016 0.5058)
					(end 0.508 0)
					(stroke
						(width 0)
						(type default)
					)
					(fill
						(type none)
					)
				)
				(arc
					(start 2.54 0)
					(mid 2.032 0.5058)
					(end 1.524 0)
					(stroke
						(width 0)
						(type default)
					)
					(fill
						(type none)
					)
				)
				(arc
					(start 3.556 0)
					(mid 3.048 0.5058)
					(end 2.54 0)
					(stroke
						(width 0)
						(type default)
					)
					(fill
						(type none)
					)
				)
				(arc
					(start 4.572 0)
					(mid 4.064 0.5058)
					(end 3.556 0)
					(stroke
						(width 0)
						(type default)
					)
					(fill
						(type none)
					)
				)
			)
			(symbol "L_3u3_3.1A_Bourns-SRP3212A_1_1"
				(pin passive line
					(at 0 0 0)
					(length 0.508)
					(name "~"
						(effects
							(font
								(size 1.27 1.27)
							)
						)
					)
					(number "1"
						(effects
							(font
								(size 1.27 1.27)
							)
						)
					)
				)
				(pin passive line
					(at 5.08 0 180)
					(length 0.508)
					(name "~"
						(effects
							(font
								(size 1.27 1.27)
							)
						)
					)
					(number "2"
						(effects
							(font
								(size 1.27 1.27)
							)
						)
					)
				)
			)
		)
	(symbol "antmicroFixedInductors:L_470n_1A_Coilcraft-PFL1609"
			(pin_numbers hide)
			(pin_names hide)
			(exclude_from_sim no)
			(in_bom yes)
			(on_board yes)
			(property "Reference" "L"
				(at 13.97 0 0)
				(effects
					(font
						(size 1.27 1.27)
						(thickness 0.15)
					)
					(justify left bottom)
				)
			)
			(property "Value" "L_470n_1A_Coilcraft-PFL1609"
				(at 13.97 -2.54 0)
				(effects
					(font
						(size 1.27 1.27)
						(thickness 0.15)
					)
					(justify left bottom)
					(hide yes)
				)
			)
			(property "Footprint" "antmicro-footprints:L_Coilcraft-PFL1609"
				(at 13.97 -7.62 0)
				(effects
					(font
						(size 1.27 1.27)
						(thickness 0.15)
					)
					(justify left bottom)
					(hide yes)
				)
			)
			(property "Datasheet" "https://www.coilcraft.com/getmedia/2f4cd442-d64d-4413-a518-12fcfd03318d/pfl1609.pdf"
				(at 13.97 -10.16 0)
				(effects
					(font
						(size 1.27 1.27)
						(thickness 0.15)
					)
					(justify left bottom)
					(hide yes)
				)
			)
			(property "Description" "Power Inductor (SMT), 6.8 µH, 9.2 A, Shielded, 12.8 A, XAL7070"
				(at 0 0 0)
				(effects
					(font
						(size 1.27 1.27)
					)
					(hide yes)
				)
			)
			(property "Val" "470n/0.99A"
				(at 13.97 -5.08 0)
				(effects
					(font
						(size 1.27 1.27)
						(thickness 0.15)
					)
					(justify left bottom)
				)
			)
			(property "Manufacturer" "Coilcraft"
				(at 13.97 -12.7 0)
				(effects
					(font
						(size 1.27 1.27)
						(thickness 0.15)
					)
					(justify left bottom)
					(hide yes)
				)
			)
			(property "MPN" "PFL1609-471"
				(at 13.97 -15.24 0)
				(effects
					(font
						(size 1.27 1.27)
						(thickness 0.15)
					)
					(justify left bottom)
					(hide yes)
				)
			)
			(property "ISat" "0.99 A"
				(at 13.97 -16.51 0)
				(effects
					(font
						(size 1.27 1.27)
					)
					(justify left)
					(hide yes)
				)
			)
			(property "IMax" "1 A"
				(at 13.97 -20.32 0)
				(effects
					(font
						(size 1.27 1.27)
						(thickness 0.15)
					)
					(justify left bottom)
					(hide yes)
				)
			)
			(property "Size" "1.07x1.8"
				(at 13.97 -22.86 0)
				(effects
					(font
						(size 1.27 1.27)
						(thickness 0.15)
					)
					(justify left bottom)
					(hide yes)
				)
			)
			(property "Author" "Antmicro"
				(at 13.97 -25.4 0)
				(effects
					(font
						(size 1.27 1.27)
						(thickness 0.15)
					)
					(justify left bottom)
					(hide yes)
				)
			)
			(property "License" "Apache-2.0"
				(at 13.97 -27.94 0)
				(effects
					(font
						(size 1.27 1.27)
						(thickness 0.15)
					)
					(justify left bottom)
					(hide yes)
				)
			)
			(property "ki_keywords" "SMT, INDUCTOR, PASSIVE"
				(at 0 0 0)
				(effects
					(font
						(size 1.27 1.27)
					)
					(hide yes)
				)
			)
			(symbol "L_470n_1A_Coilcraft-PFL1609_0_1"
				(arc
					(start 1.524 0)
					(mid 1.016 0.5058)
					(end 0.508 0)
					(stroke
						(width 0)
						(type default)
					)
					(fill
						(type none)
					)
				)
				(arc
					(start 2.54 0)
					(mid 2.032 0.5058)
					(end 1.524 0)
					(stroke
						(width 0)
						(type default)
					)
					(fill
						(type none)
					)
				)
				(arc
					(start 3.556 0)
					(mid 3.048 0.5058)
					(end 2.54 0)
					(stroke
						(width 0)
						(type default)
					)
					(fill
						(type none)
					)
				)
				(arc
					(start 4.572 0)
					(mid 4.064 0.5058)
					(end 3.556 0)
					(stroke
						(width 0)
						(type default)
					)
					(fill
						(type none)
					)
				)
			)
			(symbol "L_470n_1A_Coilcraft-PFL1609_1_1"
				(pin passive line
					(at 0 0 0)
					(length 0.508)
					(name "~"
						(effects
							(font
								(size 1.27 1.27)
							)
						)
					)
					(number "1"
						(effects
							(font
								(size 1.27 1.27)
							)
						)
					)
				)
				(pin passive line
					(at 5.08 0 180)
					(length 0.508)
					(name "~"
						(effects
							(font
								(size 1.27 1.27)
							)
						)
					)
					(number "2"
						(effects
							(font
								(size 1.27 1.27)
							)
						)
					)
				)
			)
		)
	(symbol "antmicroFixedInductors:L_6u8_1A_Coilcraft-1210POC"
			(pin_numbers hide)
			(pin_names hide)
			(exclude_from_sim no)
			(in_bom yes)
			(on_board yes)
			(property "Reference" "L"
				(at 13.97 0 0)
				(effects
					(font
						(size 1.27 1.27)
						(thickness 0.15)
					)
					(justify left bottom)
				)
			)
			(property "Value" "L_6u8_1A_Coilcraft-1210POC"
				(at 13.97 -2.54 0)
				(effects
					(font
						(size 1.27 1.27)
						(thickness 0.15)
					)
					(justify left bottom)
					(hide yes)
				)
			)
			(property "Footprint" "antmicro-footprints:L_Coilcraft-1210POC"
				(at 13.97 -7.62 0)
				(effects
					(font
						(size 1.27 1.27)
						(thickness 0.15)
					)
					(justify left bottom)
					(hide yes)
				)
			)
			(property "Datasheet" "https://www.coilcraft.com/getmedia/5e8de018-68c5-4442-84ce-d5212c44660c/1210poc.pdf"
				(at 13.97 -10.16 0)
				(effects
					(font
						(size 1.27 1.27)
						(thickness 0.15)
					)
					(justify left bottom)
					(hide yes)
				)
			)
			(property "Description" "Power Inductor (SMT), 6.8 µH, 9.2 A, Shielded, 12.8 A, XAL7070"
				(at 0 0 0)
				(effects
					(font
						(size 1.27 1.27)
					)
					(hide yes)
				)
			)
			(property "Val" "6u8/1A"
				(at 13.97 -5.08 0)
				(effects
					(font
						(size 1.27 1.27)
						(thickness 0.15)
					)
					(justify left bottom)
				)
			)
			(property "Manufacturer" "Coilcraft"
				(at 13.97 -12.7 0)
				(effects
					(font
						(size 1.27 1.27)
						(thickness 0.15)
					)
					(justify left bottom)
					(hide yes)
				)
			)
			(property "MPN" "1210POC-682"
				(at 13.97 -15.24 0)
				(effects
					(font
						(size 1.27 1.27)
						(thickness 0.15)
					)
					(justify left bottom)
					(hide yes)
				)
			)
			(property "ISat" "1 A"
				(at 13.97 -16.51 0)
				(effects
					(font
						(size 1.27 1.27)
					)
					(justify left)
					(hide yes)
				)
			)
			(property "IMax" "1.36 A"
				(at 13.97 -20.32 0)
				(effects
					(font
						(size 1.27 1.27)
						(thickness 0.15)
					)
					(justify left bottom)
					(hide yes)
				)
			)
			(property "Size" "2.67x3.3"
				(at 13.97 -22.86 0)
				(effects
					(font
						(size 1.27 1.27)
						(thickness 0.15)
					)
					(justify left bottom)
					(hide yes)
				)
			)
			(property "Author" "Antmicro"
				(at 13.97 -25.4 0)
				(effects
					(font
						(size 1.27 1.27)
						(thickness 0.15)
					)
					(justify left bottom)
					(hide yes)
				)
			)
			(property "License" "Apache-2.0"
				(at 13.97 -27.94 0)
				(effects
					(font
						(size 1.27 1.27)
						(thickness 0.15)
					)
					(justify left bottom)
					(hide yes)
				)
			)
			(property "ki_keywords" "SMT, INDUCTOR, PASSIVE"
				(at 0 0 0)
				(effects
					(font
						(size 1.27 1.27)
					)
					(hide yes)
				)
			)
			(symbol "L_6u8_1A_Coilcraft-1210POC_0_1"
				(arc
					(start 1.524 0)
					(mid 1.016 0.5058)
					(end 0.508 0)
					(stroke
						(width 0)
						(type default)
					)
					(fill
						(type none)
					)
				)
				(arc
					(start 2.54 0)
					(mid 2.032 0.5058)
					(end 1.524 0)
					(stroke
						(width 0)
						(type default)
					)
					(fill
						(type none)
					)
				)
				(arc
					(start 3.556 0)
					(mid 3.048 0.5058)
					(end 2.54 0)
					(stroke
						(width 0)
						(type default)
					)
					(fill
						(type none)
					)
				)
				(arc
					(start 4.572 0)
					(mid 4.064 0.5058)
					(end 3.556 0)
					(stroke
						(width 0)
						(type default)
					)
					(fill
						(type none)
					)
				)
			)
			(symbol "L_6u8_1A_Coilcraft-1210POC_1_1"
				(pin passive line
					(at 0 0 0)
					(length 0.508)
					(name "~"
						(effects
							(font
								(size 1.27 1.27)
							)
						)
					)
					(number "1"
						(effects
							(font
								(size 1.27 1.27)
							)
						)
					)
				)
				(pin passive line
					(at 5.08 0 180)
					(length 0.508)
					(name "~"
						(effects
							(font
								(size 1.27 1.27)
							)
						)
					)
					(number "2"
						(effects
							(font
								(size 1.27 1.27)
							)
						)
					)
				)
			)
		)
	(symbol "antmicroInterfaceControllers:MAX96717GTJ_VY+"
			(exclude_from_sim no)
			(in_bom yes)
			(on_board yes)
			(property "Reference" "U"
				(at 48.26 -2.54 0)
				(effects
					(font
						(size 1.27 1.27)
					)
					(justify left bottom)
				)
			)
			(property "Value" "MAX96717GTJ_VY+"
				(at 48.26 -5.08 0)
				(effects
					(font
						(size 1.27 1.27)
					)
					(justify left bottom)
					(hide yes)
				)
			)
			(property "Footprint" "antmicro-footprints:TQFN-32-1EP_5x5mm_P0.5mm"
				(at 48.26 -7.62 0)
				(effects
					(font
						(size 1.27 1.27)
					)
					(justify left bottom)
					(hide yes)
				)
			)
			(property "Datasheet" "https://www.analog.com/media/en/technical-documentation/data-sheets/max96717.pdf"
				(at 48.26 -10.16 0)
				(effects
					(font
						(size 1.27 1.27)
					)
					(justify left bottom)
					(hide yes)
				)
			)
			(property "Description" "CSI-2 to GMSL2 Serializer"
				(at 0 0 0)
				(effects
					(font
						(size 1.27 1.27)
					)
					(hide yes)
				)
			)
			(property "MPN" "MAX96717GTJ/VY+"
				(at 48.26 -12.7 0)
				(effects
					(font
						(size 1.27 1.27)
					)
					(justify left bottom)
				)
			)
			(property "Manufacturer" "Analog Devices"
				(at 48.26 -15.24 0)
				(effects
					(font
						(size 1.27 1.27)
					)
					(justify left bottom)
					(hide yes)
				)
			)
			(property "Author" "Antmicro"
				(at 48.26 -17.78 0)
				(effects
					(font
						(size 1.27 1.27)
					)
					(justify left bottom)
					(hide yes)
				)
			)
			(property "License" "Apache-2.0"
				(at 48.26 -20.32 0)
				(effects
					(font
						(size 1.27 1.27)
					)
					(justify left bottom)
					(hide yes)
				)
			)
			(property "ki_keywords" "SMT, INTERFACE, IC, GMSL"
				(at 0 0 0)
				(effects
					(font
						(size 1.27 1.27)
					)
					(hide yes)
				)
			)
			(symbol "MAX96717GTJ_VY+_1_1"
				(rectangle
					(start 2.54 2.54)
					(end 25.4 -55.88)
					(stroke
						(width 0.254)
						(type default)
					)
					(fill
						(type background)
					)
				)
				(pin input line
					(at 0 -35.56 0)
					(length 2.54)
					(name "PWDNB"
						(effects
							(font
								(size 1.27 1.27)
							)
						)
					)
					(number "1"
						(effects
							(font
								(size 1.27 1.27)
							)
						)
					)
				)
				(pin passive line
					(at 0 -38.1 0)
					(length 2.54)
					(name "XRES"
						(effects
							(font
								(size 1.27 1.27)
							)
						)
					)
					(number "10"
						(effects
							(font
								(size 1.27 1.27)
							)
						)
					)
				)
				(pin power_in line
					(at 0 -2.54 0)
					(length 2.54)
					(name "VDD18"
						(effects
							(font
								(size 1.27 1.27)
							)
						)
					)
					(number "11"
						(effects
							(font
								(size 1.27 1.27)
							)
						)
					)
				)
				(pin bidirectional line
					(at 0 -17.78 0)
					(length 2.54)
					(name "SIOP"
						(effects
							(font
								(size 1.27 1.27)
							)
						)
					)
					(number "12"
						(effects
							(font
								(size 1.27 1.27)
							)
						)
					)
				)
				(pin bidirectional line
					(at 0 -20.32 0)
					(length 2.54)
					(name "SION"
						(effects
							(font
								(size 1.27 1.27)
							)
						)
					)
					(number "13"
						(effects
							(font
								(size 1.27 1.27)
							)
						)
					)
				)
				(pin power_in line
					(at 0 -40.64 0)
					(length 2.54)
					(name "CAP_VDD"
						(effects
							(font
								(size 1.27 1.27)
							)
						)
					)
					(number "14"
						(effects
							(font
								(size 1.27 1.27)
							)
						)
					)
				)
				(pin power_in line
					(at 0 0 0)
					(length 2.54)
					(name "VDD"
						(effects
							(font
								(size 1.27 1.27)
							)
						)
					)
					(number "15"
						(effects
							(font
								(size 1.27 1.27)
							)
						)
					)
				)
				(pin power_in line
					(at 0 -5.08 0)
					(length 2.54)
					(name "VDDIO"
						(effects
							(font
								(size 1.27 1.27)
							)
						)
					)
					(number "16"
						(effects
							(font
								(size 1.27 1.27)
							)
						)
					)
				)
				(pin bidirectional line
					(at 27.94 -35.56 180)
					(length 2.54)
					(name "MFP3"
						(effects
							(font
								(size 1.27 1.27)
							)
						)
					)
					(number "17"
						(effects
							(font
								(size 1.27 1.27)
							)
						)
					)
					(alternate "ADC0" input line)
					(alternate "ERRB" output line)
					(alternate "GPIO3" bidirectional line)
					(alternate "LOCK" output line)
					(alternate "VTG3" output line)
				)
				(pin bidirectional line
					(at 27.94 -38.1 180)
					(length 2.54)
					(name "MFP4"
						(effects
							(font
								(size 1.27 1.27)
							)
						)
					)
					(number "18"
						(effects
							(font
								(size 1.27 1.27)
							)
						)
					)
					(alternate "DPLL_OUT" output line)
					(alternate "GPIO4" bidirectional line)
					(alternate "RCLKOUT" output line)
					(alternate "RO" input line)
					(alternate "SS2" output line)
					(alternate "VTG4" output line)
				)
				(pin input line
					(at 27.94 -15.24 180)
					(length 2.54)
					(name "D2P"
						(effects
							(font
								(size 1.27 1.27)
							)
						)
					)
					(number "19"
						(effects
							(font
								(size 1.27 1.27)
							)
						)
					)
				)
				(pin bidirectional line
					(at 27.94 -27.94 180)
					(length 2.54)
					(name "MFP0"
						(effects
							(font
								(size 1.27 1.27)
							)
						)
					)
					(number "2"
						(effects
							(font
								(size 1.27 1.27)
							)
						)
					)
					(alternate "GPIO0" bidirectional line)
					(alternate "SCLK" output line)
					(alternate "VTG0" output line)
				)
				(pin input line
					(at 27.94 -17.78 180)
					(length 2.54)
					(name "D2N"
						(effects
							(font
								(size 1.27 1.27)
							)
						)
					)
					(number "20"
						(effects
							(font
								(size 1.27 1.27)
							)
						)
					)
				)
				(pin bidirectional line
					(at 27.94 -40.64 180)
					(length 2.54)
					(name "MFP5"
						(effects
							(font
								(size 1.27 1.27)
							)
						)
					)
					(number "21"
						(effects
							(font
								(size 1.27 1.27)
							)
						)
					)
					(alternate "ADC1" input line)
					(alternate "LMN0" input line)
					(alternate "ODO5_GPI5" input line)
				)
				(pin bidirectional line
					(at 27.94 -43.18 180)
					(length 2.54)
					(name "MFP6"
						(effects
							(font
								(size 1.27 1.27)
							)
						)
					)
					(number "22"
						(effects
							(font
								(size 1.27 1.27)
							)
						)
					)
					(alternate "ADC2" input line)
					(alternate "LMN1" input line)
					(alternate "ODO6_GPI6" input line)
				)
				(pin input line
					(at 27.94 -20.32 180)
					(length 2.54)
					(name "D3P"
						(effects
							(font
								(size 1.27 1.27)
							)
						)
					)
					(number "23"
						(effects
							(font
								(size 1.27 1.27)
							)
						)
					)
				)
				(pin input line
					(at 27.94 -22.86 180)
					(length 2.54)
					(name "D3N"
						(effects
							(font
								(size 1.27 1.27)
							)
						)
					)
					(number "24"
						(effects
							(font
								(size 1.27 1.27)
							)
						)
					)
				)
				(pin input line
					(at 27.94 -5.08 180)
					(length 2.54)
					(name "D0P"
						(effects
							(font
								(size 1.27 1.27)
							)
						)
					)
					(number "25"
						(effects
							(font
								(size 1.27 1.27)
							)
						)
					)
				)
				(pin input line
					(at 27.94 -7.62 180)
					(length 2.54)
					(name "D0N"
						(effects
							(font
								(size 1.27 1.27)
							)
						)
					)
					(number "26"
						(effects
							(font
								(size 1.27 1.27)
							)
						)
					)
				)
				(pin input line
					(at 27.94 0 180)
					(length 2.54)
					(name "CKP"
						(effects
							(font
								(size 1.27 1.27)
							)
						)
					)
					(number "27"
						(effects
							(font
								(size 1.27 1.27)
							)
						)
					)
				)
				(pin input line
					(at 27.94 -2.54 180)
					(length 2.54)
					(name "CKN"
						(effects
							(font
								(size 1.27 1.27)
							)
						)
					)
					(number "28"
						(effects
							(font
								(size 1.27 1.27)
							)
						)
					)
				)
				(pin input line
					(at 27.94 -10.16 180)
					(length 2.54)
					(name "D1P"
						(effects
							(font
								(size 1.27 1.27)
							)
						)
					)
					(number "29"
						(effects
							(font
								(size 1.27 1.27)
							)
						)
					)
				)
				(pin bidirectional line
					(at 27.94 -30.48 180)
					(length 2.54)
					(name "MFP1"
						(effects
							(font
								(size 1.27 1.27)
							)
						)
					)
					(number "3"
						(effects
							(font
								(size 1.27 1.27)
							)
						)
					)
					(alternate "BNE" output line)
					(alternate "CFG0" input line)
					(alternate "GPO1" output line)
					(alternate "SS1" output line)
					(alternate "VTG1" output line)
				)
				(pin input line
					(at 27.94 -12.7 180)
					(length 2.54)
					(name "D1N"
						(effects
							(font
								(size 1.27 1.27)
							)
						)
					)
					(number "30"
						(effects
							(font
								(size 1.27 1.27)
							)
						)
					)
				)
				(pin bidirectional line
					(at 27.94 -45.72 180)
					(length 2.54)
					(name "MFP7"
						(effects
							(font
								(size 1.27 1.27)
							)
						)
					)
					(number "31"
						(effects
							(font
								(size 1.27 1.27)
							)
						)
					)
					(alternate "GPI7" input line)
					(alternate "GPIO7" bidirectional line)
					(alternate "LOCK (Alt)" output line)
					(alternate "MOSI" bidirectional line)
					(alternate "RX1" input line)
					(alternate "SDA1" open_collector line)
					(alternate "VTG7" output line)
				)
				(pin bidirectional line
					(at 27.94 -48.26 180)
					(length 2.54)
					(name "MFP8"
						(effects
							(font
								(size 1.27 1.27)
							)
						)
					)
					(number "32"
						(effects
							(font
								(size 1.27 1.27)
							)
						)
					)
					(alternate "ERRB (Alt)" output line)
					(alternate "GPIO8" bidirectional line)
					(alternate "MISO" input line)
					(alternate "MS" input line)
					(alternate "SCL1" open_collector line)
					(alternate "TX1" output line)
					(alternate "VTG8" output line)
				)
				(pin power_in line
					(at 0 -53.34 0)
					(length 2.54)
					(name "GND"
						(effects
							(font
								(size 1.27 1.27)
							)
						)
					)
					(number "33"
						(effects
							(font
								(size 1.27 1.27)
							)
						)
					)
				)
				(pin bidirectional line
					(at 27.94 -33.02 180)
					(length 2.54)
					(name "MFP2"
						(effects
							(font
								(size 1.27 1.27)
							)
						)
					)
					(number "4"
						(effects
							(font
								(size 1.27 1.27)
							)
						)
					)
					(alternate "CFG1" input line)
					(alternate "DPLL_OUT(Alt)" output line)
					(alternate "GPO2" output line)
					(alternate "RCLKOUT(Alt)" output line)
					(alternate "VTG2" output line)
				)
				(pin bidirectional line
					(at 27.94 -50.8 180)
					(length 2.54)
					(name "MFP9"
						(effects
							(font
								(size 1.27 1.27)
							)
						)
					)
					(number "5"
						(effects
							(font
								(size 1.27 1.27)
							)
						)
					)
					(alternate "OD09_GPI9" bidirectional line)
					(alternate "SDA2_RX2" bidirectional line)
					(alternate "SDA_RX" bidirectional line)
				)
				(pin bidirectional line
					(at 27.94 -53.34 180)
					(length 2.54)
					(name "MFP10"
						(effects
							(font
								(size 1.27 1.27)
							)
						)
					)
					(number "6"
						(effects
							(font
								(size 1.27 1.27)
							)
						)
					)
					(alternate "ODO10_GPI10" bidirectional line)
					(alternate "SCL2_TX2" bidirectional line)
					(alternate "SCL_TX*" bidirectional line)
				)
				(pin power_in line
					(at 0 -12.7 0)
					(length 2.54)
					(name "VREF"
						(effects
							(font
								(size 1.27 1.27)
							)
						)
					)
					(number "7"
						(effects
							(font
								(size 1.27 1.27)
							)
						)
					)
				)
				(pin bidirectional line
					(at 0 -27.94 0)
					(length 2.54)
					(name "X1/OSC"
						(effects
							(font
								(size 1.27 1.27)
							)
						)
					)
					(number "8"
						(effects
							(font
								(size 1.27 1.27)
							)
						)
					)
				)
				(pin bidirectional line
					(at 0 -30.48 0)
					(length 2.54)
					(name "X2"
						(effects
							(font
								(size 1.27 1.27)
							)
						)
					)
					(number "9"
						(effects
							(font
								(size 1.27 1.27)
							)
						)
					)
				)
			)
		)
	(symbol "antmicroLEDIndicationDiscrete:LED_G_0603_LTST-C190GKT"
			(pin_numbers hide)
			(pin_names hide)
			(exclude_from_sim no)
			(in_bom yes)
			(on_board yes)
			(property "Reference" "D"
				(at 22.86 -2.54 0)
				(effects
					(font
						(size 1.27 1.27)
						(thickness 0.15)
					)
					(justify left bottom)
				)
			)
			(property "Value" "LED_G_0603_LTST-C190GKT"
				(at 22.86 -7.62 0)
				(effects
					(font
						(size 1.27 1.27)
						(thickness 0.15)
					)
					(justify left bottom)
					(hide yes)
				)
			)
			(property "Footprint" "antmicro-footprints:LED_0603_1608Metric_G"
				(at 22.86 -10.16 0)
				(effects
					(font
						(size 1.27 1.27)
						(thickness 0.15)
					)
					(justify left bottom)
					(hide yes)
				)
			)
			(property "Datasheet" "https://media.digikey.com/pdf/Data%20Sheets/Lite-On%20PDFs/LTST-C190GKT.pdf"
				(at 22.86 -12.7 0)
				(effects
					(font
						(size 1.27 1.27)
						(thickness 0.15)
					)
					(justify left bottom)
					(hide yes)
				)
			)
			(property "Description" "LED, Green, SMD, 0603, 20 mA, 2.1 V, 569 nm"
				(at 0 0 0)
				(effects
					(font
						(size 1.27 1.27)
					)
					(hide yes)
				)
			)
			(property "MPN" "LTST-C190GKT"
				(at 22.86 -15.24 0)
				(effects
					(font
						(size 1.27 1.27)
						(thickness 0.15)
					)
					(justify left bottom)
					(hide yes)
				)
			)
			(property "Manufacturer" "Lite-On"
				(at 22.86 -17.78 0)
				(effects
					(font
						(size 1.27 1.27)
						(thickness 0.15)
					)
					(justify left bottom)
					(hide yes)
				)
			)
			(property "Color" "Green"
				(at 22.86 -5.08 0)
				(effects
					(font
						(size 1.27 1.27)
					)
					(justify left bottom)
				)
			)
			(property "Author" "Antmicro"
				(at 22.86 -20.32 0)
				(effects
					(font
						(size 1.27 1.27)
						(thickness 0.15)
					)
					(justify left bottom)
					(hide yes)
				)
			)
			(property "License" "Apache-2.0"
				(at 22.86 -22.86 0)
				(effects
					(font
						(size 1.27 1.27)
						(thickness 0.15)
					)
					(justify left bottom)
					(hide yes)
				)
			)
			(property "ki_keywords" "SMT, DIODE, SEMICONDUCTOR, LED"
				(at 0 0 0)
				(effects
					(font
						(size 1.27 1.27)
					)
					(hide yes)
				)
			)
			(symbol "LED_G_0603_LTST-C190GKT_0_1"
				(polyline
					(pts
						(xy 1.905 0) (xy 0.635 0)
					)
					(stroke
						(width 0)
						(type default)
					)
					(fill
						(type none)
					)
				)
				(polyline
					(pts
						(xy 4.445 0) (xy 3.175 0)
					)
					(stroke
						(width 0)
						(type default)
					)
					(fill
						(type none)
					)
				)
			)
			(symbol "LED_G_0603_LTST-C190GKT_1_1"
				(polyline
					(pts
						(xy 1.778 1.016) (xy 1.778 -1.016)
					)
					(stroke
						(width 0.254)
						(type default)
					)
					(fill
						(type none)
					)
				)
				(polyline
					(pts
						(xy 3.302 1.016) (xy 3.302 -1.016) (xy 1.778 0) (xy 3.302 1.016)
					)
					(stroke
						(width 0.254)
						(type default)
					)
					(fill
						(type outline)
					)
				)
				(polyline
					(pts
						(xy 1.143 2.286) (xy 1.143 1.778) (xy 1.143 2.286) (xy 1.651 2.286) (xy 1.143 2.286) (xy 2.159 1.27)
					)
					(stroke
						(width 0.254)
						(type default)
					)
					(fill
						(type none)
					)
				)
				(polyline
					(pts
						(xy 2.159 2.54) (xy 2.159 2.032) (xy 2.159 2.54) (xy 2.667 2.54) (xy 2.159 2.54) (xy 3.048 1.651)
					)
					(stroke
						(width 0.254)
						(type default)
					)
					(fill
						(type none)
					)
				)
				(pin passive line
					(at 0 0 0)
					(length 0.635)
					(name "C"
						(effects
							(font
								(size 1.27 1.27)
							)
						)
					)
					(number "1"
						(effects
							(font
								(size 1.27 1.27)
							)
						)
					)
				)
				(pin passive line
					(at 5.08 0 180)
					(length 0.635)
					(name "A"
						(effects
							(font
								(size 1.27 1.27)
							)
						)
					)
					(number "2"
						(effects
							(font
								(size 1.27 1.27)
							)
						)
					)
				)
			)
		)
	(symbol "antmicroMechanicalParts:MP_Pad6mm_Drill3mm"
			(pin_names hide)
			(exclude_from_sim no)
			(in_bom no)
			(on_board yes)
			(property "Reference" "MP"
				(at 20.32 -2.54 0)
				(effects
					(font
						(size 1.27 1.27)
						(thickness 0.15)
					)
					(justify left bottom)
				)
			)
			(property "Value" "MP_Pad6mm_Drill3mm"
				(at 20.32 -5.08 0)
				(effects
					(font
						(size 1.27 1.27)
						(thickness 0.15)
					)
					(justify left bottom)
				)
			)
			(property "Footprint" "antmicro-footprints:MP_Pad6mm_Drill3mm"
				(at 20.32 -7.62 0)
				(effects
					(font
						(size 1.27 1.27)
						(thickness 0.15)
					)
					(justify left bottom)
					(hide yes)
				)
			)
			(property "Datasheet" ""
				(at 16.84 -15.57 0)
				(effects
					(font
						(size 1.27 1.27)
						(thickness 0.15)
					)
					(justify left bottom)
					(hide yes)
				)
			)
			(property "Description" "Mechanical part"
				(at 0 0 0)
				(effects
					(font
						(size 1.27 1.27)
					)
					(hide yes)
				)
			)
			(property "Author" "Antmicro"
				(at 20.32 -10.16 0)
				(effects
					(font
						(size 1.27 1.27)
						(thickness 0.15)
					)
					(justify left bottom)
					(hide yes)
				)
			)
			(property "License" "Apache-2.0"
				(at 20.32 -12.7 0)
				(effects
					(font
						(size 1.27 1.27)
						(thickness 0.15)
					)
					(justify left bottom)
					(hide yes)
				)
			)
			(property "ki_keywords" "MECHANICAL"
				(at 0 0 0)
				(effects
					(font
						(size 1.27 1.27)
					)
					(hide yes)
				)
			)
			(symbol "MP_Pad6mm_Drill3mm_1_1"
				(circle
					(center 5.08 0)
					(radius 1.27)
					(stroke
						(width 0.254)
						(type default)
					)
					(fill
						(type background)
					)
				)
				(circle
					(center 5.08 0)
					(radius 2.54)
					(stroke
						(width 0.254)
						(type default)
					)
					(fill
						(type background)
					)
				)
				(pin passive line
					(at 0 0 0)
					(length 2.54)
					(name "~"
						(effects
							(font
								(size 1.27 1.27)
							)
						)
					)
					(number "1"
						(effects
							(font
								(size 1.27 1.27)
							)
						)
					)
				)
			)
		)
	(symbol "antmicroPMICPowerDistributionSwitchesLoadDrivers:REF3012AIDBZT"
			(exclude_from_sim no)
			(in_bom yes)
			(on_board yes)
			(property "Reference" "U"
				(at 33.02 -6.35 0)
				(effects
					(font
						(size 1.27 1.27)
						(thickness 0.15)
					)
					(justify left bottom)
				)
			)
			(property "Value" "REF3012AIDBZT"
				(at 33.02 -15.24 0)
				(effects
					(font
						(size 1.27 1.27)
						(thickness 0.15)
					)
					(justify left bottom)
					(hide yes)
				)
			)
			(property "Footprint" "antmicro-footprints:SOT-23-3"
				(at 33.02 -10.16 0)
				(effects
					(font
						(size 1.27 1.27)
						(thickness 0.15)
					)
					(justify left bottom)
					(hide yes)
				)
			)
			(property "Datasheet" "https://www.ti.com/lit/gpn/REF3012"
				(at 33.02 -12.7 0)
				(effects
					(font
						(size 1.27 1.27)
						(thickness 0.15)
					)
					(justify left bottom)
					(hide yes)
				)
			)
			(property "Description" "Voltage Reference, Low Power, Low Dropout, Series"
				(at 0 0 0)
				(effects
					(font
						(size 1.27 1.27)
					)
					(hide yes)
				)
			)
			(property "MPN" "REF3012AIDBZT"
				(at 33.02 -8.255 0)
				(effects
					(font
						(size 1.27 1.27)
						(thickness 0.15)
					)
					(justify left bottom)
				)
			)
			(property "Manufacturer" "Texas Instruments"
				(at 33.02 -17.78 0)
				(effects
					(font
						(size 1.27 1.27)
						(thickness 0.15)
					)
					(justify left bottom)
					(hide yes)
				)
			)
			(property "Author" "Antmicro"
				(at 33.02 -20.32 0)
				(effects
					(font
						(size 1.27 1.27)
						(thickness 0.15)
					)
					(justify left bottom)
					(hide yes)
				)
			)
			(property "License" "Apache-2.0"
				(at 33.02 -22.86 0)
				(effects
					(font
						(size 1.27 1.27)
						(thickness 0.15)
					)
					(justify left bottom)
					(hide yes)
				)
			)
			(property "ki_keywords" "SMT, PMIC, IC, POWER, SWITCH, DRIVER"
				(at 0 0 0)
				(effects
					(font
						(size 1.27 1.27)
					)
					(hide yes)
				)
			)
			(symbol "REF3012AIDBZT_1_1"
				(rectangle
					(start 2.54 1.27)
					(end 15.24 -5.08)
					(stroke
						(width 0.254)
						(type default)
					)
					(fill
						(type background)
					)
				)
				(pin power_in line
					(at 0 0 0)
					(length 2.54)
					(name "IN"
						(effects
							(font
								(size 1.27 1.27)
							)
						)
					)
					(number "1"
						(effects
							(font
								(size 1.27 1.27)
							)
						)
					)
				)
				(pin output line
					(at 17.78 0 180)
					(length 2.54)
					(name "OUT"
						(effects
							(font
								(size 1.27 1.27)
							)
						)
					)
					(number "2"
						(effects
							(font
								(size 1.27 1.27)
							)
						)
					)
				)
				(pin passive line
					(at 0 -3.81 0)
					(length 2.54)
					(name "GND"
						(effects
							(font
								(size 1.27 1.27)
							)
						)
					)
					(number "3"
						(effects
							(font
								(size 1.27 1.27)
							)
						)
					)
				)
			)
		)
	(symbol "antmicroPMICVoltageRegulatorsLinear:TLV73312PDBVT"
			(exclude_from_sim no)
			(in_bom yes)
			(on_board yes)
			(property "Reference" "U"
				(at 35.56 -2.54 0)
				(effects
					(font
						(size 1.27 1.27)
						(thickness 0.15)
					)
					(justify left bottom)
				)
			)
			(property "Value" "TLV73312PDBVT"
				(at 35.56 -5.08 0)
				(effects
					(font
						(size 1.27 1.27)
						(thickness 0.15)
					)
					(justify left bottom)
					(hide yes)
				)
			)
			(property "Footprint" "antmicro-footprints:SOT-23-5"
				(at 35.56 -7.62 0)
				(effects
					(font
						(size 1.27 1.27)
						(thickness 0.15)
					)
					(justify left bottom)
					(hide yes)
				)
			)
			(property "Datasheet" "https://www.ti.com/lit/ds/symlink/tlv733p.pdf?HQS=dis-mous-null-mousermode-dsf-pf-null-wwe&ts=1676978230940&ref_url=https%253A%252F%252Fwww.mouser.com%252F"
				(at 35.56 -10.16 0)
				(effects
					(font
						(size 1.27 1.27)
						(thickness 0.15)
					)
					(justify left bottom)
					(hide yes)
				)
			)
			(property "Description" "Fixed LDO Voltage Regulator, 1.4V to 5.5V, 122mV Dropout, 1.2Vout, 300mAout, SOT-23-5"
				(at 0 0 0)
				(effects
					(font
						(size 1.27 1.27)
					)
					(hide yes)
				)
			)
			(property "MPN" "TLV73312PDBVT"
				(at 35.56 -12.7 0)
				(effects
					(font
						(size 1.27 1.27)
						(thickness 0.15)
					)
					(justify left bottom)
				)
			)
			(property "Manufacturer" "Texas Instruments"
				(at 35.56 -15.24 0)
				(effects
					(font
						(size 1.27 1.27)
						(thickness 0.15)
					)
					(justify left bottom)
					(hide yes)
				)
			)
			(property "Author" "Antmicro"
				(at 35.56 -17.78 0)
				(effects
					(font
						(size 1.27 1.27)
						(thickness 0.15)
					)
					(justify left bottom)
					(hide yes)
				)
			)
			(property "License" "Apache-2.0"
				(at 35.56 -20.32 0)
				(effects
					(font
						(size 1.27 1.27)
						(thickness 0.15)
					)
					(justify left bottom)
					(hide yes)
				)
			)
			(property "ki_keywords" "SMT, PMIC, IC, LDO, LINEAR, VOLTAGE, REGULATOR"
				(at 0 0 0)
				(effects
					(font
						(size 1.27 1.27)
					)
					(hide yes)
				)
			)
			(symbol "TLV73312PDBVT_1_1"
				(rectangle
					(start 2.54 2.54)
					(end 17.78 -5.08)
					(stroke
						(width 0.254)
						(type default)
					)
					(fill
						(type background)
					)
				)
				(pin power_in line
					(at 0 0 0)
					(length 2.54)
					(name "VIN"
						(effects
							(font
								(size 1.27 1.27)
							)
						)
					)
					(number "1"
						(effects
							(font
								(size 1.27 1.27)
							)
						)
					)
				)
				(pin power_in line
					(at 20.32 -2.54 180)
					(length 2.54)
					(name "GND"
						(effects
							(font
								(size 1.27 1.27)
							)
						)
					)
					(number "2"
						(effects
							(font
								(size 1.27 1.27)
							)
						)
					)
				)
				(pin input line
					(at 0 -2.54 0)
					(length 2.54)
					(name "EN"
						(effects
							(font
								(size 1.27 1.27)
							)
						)
					)
					(number "3"
						(effects
							(font
								(size 1.27 1.27)
							)
						)
					)
				)
				(pin no_connect line
					(at 20.32 -3.81 180)
					(length 2.54) hide
					(name "NC"
						(effects
							(font
								(size 1.27 1.27)
							)
						)
					)
					(number "4"
						(effects
							(font
								(size 1.27 1.27)
							)
						)
					)
				)
				(pin power_out line
					(at 20.32 0 180)
					(length 2.54)
					(name "VOUT"
						(effects
							(font
								(size 1.27 1.27)
							)
						)
					)
					(number "5"
						(effects
							(font
								(size 1.27 1.27)
							)
						)
					)
				)
			)
		)
	(symbol "antmicroResistors0402:R_0R_0402"
			(pin_numbers hide)
			(pin_names hide)
			(exclude_from_sim no)
			(in_bom yes)
			(on_board yes)
			(property "Reference" "R"
				(at 20.32 -5.08 0)
				(effects
					(font
						(size 1.27 1.27)
						(thickness 0.15)
					)
					(justify left bottom)
				)
			)
			(property "Value" "R_0R_0402"
				(at 20.32 -12.7 0)
				(effects
					(font
						(size 1.27 1.27)
						(thickness 0.15)
					)
					(justify left bottom)
					(hide yes)
				)
			)
			(property "Footprint" "antmicro-footprints:R_0402_1005Metric"
				(at 20.32 -15.24 0)
				(effects
					(font
						(size 1.27 1.27)
						(thickness 0.15)
					)
					(justify left bottom)
					(hide yes)
				)
			)
			(property "Datasheet" "https://industrial.panasonic.com/cdbs/www-data/pdf/RDA0000/AOA0000C301.pdf"
				(at 20.32 -17.78 0)
				(effects
					(font
						(size 1.27 1.27)
						(thickness 0.15)
					)
					(justify left bottom)
					(hide yes)
				)
			)
			(property "Description" "SMD Chip Resistor, Jumper, 0 ohm, 100 mW, 0402 [1005 Metric], Thick Film, General Purpose"
				(at 0 0 0)
				(effects
					(font
						(size 1.27 1.27)
					)
					(hide yes)
				)
			)
			(property "MPN" "ERJ2GE0R00X"
				(at 20.32 -20.32 0)
				(effects
					(font
						(size 1.27 1.27)
						(thickness 0.15)
					)
					(justify left bottom)
					(hide yes)
				)
			)
			(property "Manufacturer" "Panasonic"
				(at 20.32 -22.86 0)
				(effects
					(font
						(size 1.27 1.27)
						(thickness 0.15)
					)
					(justify left bottom)
					(hide yes)
				)
			)
			(property "License" "Apache-2.0"
				(at 20.32 -25.4 0)
				(effects
					(font
						(size 1.27 1.27)
						(thickness 0.15)
					)
					(justify left bottom)
					(hide yes)
				)
			)
			(property "Author" "Antmicro"
				(at 20.32 -27.94 0)
				(effects
					(font
						(size 1.27 1.27)
						(thickness 0.15)
					)
					(justify left bottom)
					(hide yes)
				)
			)
			(property "Val" "0R"
				(at 20.32 -7.62 0)
				(effects
					(font
						(size 1.27 1.27)
						(thickness 0.15)
					)
					(justify left bottom)
				)
			)
			(property "Tolerance" "~"
				(at 20.32 -10.16 0)
				(effects
					(font
						(size 1.27 1.27)
					)
					(justify left bottom)
					(hide yes)
				)
			)
			(property "Current" "1A"
				(at 20.32 -30.48 0)
				(effects
					(font
						(size 1.27 1.27)
						(thickness 0.15)
					)
					(justify left bottom)
					(hide yes)
				)
			)
			(property "ki_keywords" "0402, SMT, RESISTOR, PASSIVE"
				(at 0 0 0)
				(effects
					(font
						(size 1.27 1.27)
					)
					(hide yes)
				)
			)
			(symbol "R_0R_0402_0_1"
				(rectangle
					(start 0.635 0.889)
					(end 4.445 -0.889)
					(stroke
						(width 0.254)
						(type default)
					)
					(fill
						(type none)
					)
				)
			)
			(symbol "R_0R_0402_1_1"
				(pin passive line
					(at 0 0 0)
					(length 0.635)
					(name "~"
						(effects
							(font
								(size 1.27 1.27)
							)
						)
					)
					(number "1"
						(effects
							(font
								(size 1.27 1.27)
							)
						)
					)
				)
				(pin passive line
					(at 5.08 0 180)
					(length 0.635)
					(name "~"
						(effects
							(font
								(size 1.27 1.27)
							)
						)
					)
					(number "2"
						(effects
							(font
								(size 1.27 1.27)
							)
						)
					)
				)
			)
		)
	(symbol "antmicroResistors0402:R_100R_0402"
			(pin_numbers hide)
			(pin_names hide)
			(exclude_from_sim no)
			(in_bom yes)
			(on_board yes)
			(property "Reference" "R"
				(at 20.32 -5.08 0)
				(effects
					(font
						(size 1.27 1.27)
						(thickness 0.15)
					)
					(justify left bottom)
				)
			)
			(property "Value" "R_100R_0402"
				(at 20.32 -12.7 0)
				(effects
					(font
						(size 1.27 1.27)
						(thickness 0.15)
					)
					(justify left bottom)
					(hide yes)
				)
			)
			(property "Footprint" "antmicro-footprints:R_0402_1005Metric"
				(at 20.32 -15.24 0)
				(effects
					(font
						(size 1.27 1.27)
						(thickness 0.15)
					)
					(justify left bottom)
					(hide yes)
				)
			)
			(property "Datasheet" "https://www.bourns.com/docs/product-datasheets/cr.pdf"
				(at 20.32 -17.78 0)
				(effects
					(font
						(size 1.27 1.27)
						(thickness 0.15)
					)
					(justify left bottom)
					(hide yes)
				)
			)
			(property "Description" "SMD Chip Resistor, 100 ohm, ± 1%, 62.5 mW, 0402 [1005 Metric], Thick Film, General Purpose"
				(at 0 0 0)
				(effects
					(font
						(size 1.27 1.27)
					)
					(hide yes)
				)
			)
			(property "MPN" "CR0402-FX-1000GLF"
				(at 20.32 -20.32 0)
				(effects
					(font
						(size 1.27 1.27)
						(thickness 0.15)
					)
					(justify left bottom)
					(hide yes)
				)
			)
			(property "Manufacturer" "Bourns"
				(at 20.32 -22.86 0)
				(effects
					(font
						(size 1.27 1.27)
						(thickness 0.15)
					)
					(justify left bottom)
					(hide yes)
				)
			)
			(property "License" "Apache-2.0"
				(at 20.32 -25.4 0)
				(effects
					(font
						(size 1.27 1.27)
						(thickness 0.15)
					)
					(justify left bottom)
					(hide yes)
				)
			)
			(property "Author" "Antmicro"
				(at 20.32 -27.94 0)
				(effects
					(font
						(size 1.27 1.27)
						(thickness 0.15)
					)
					(justify left bottom)
					(hide yes)
				)
			)
			(property "Val" "100R"
				(at 20.32 -7.62 0)
				(effects
					(font
						(size 1.27 1.27)
						(thickness 0.15)
					)
					(justify left bottom)
				)
			)
			(property "Tolerance" "1%"
				(at 20.32 -10.16 0)
				(effects
					(font
						(size 1.27 1.27)
					)
					(justify left bottom)
					(hide yes)
				)
			)
			(property "ki_keywords" "0402, SMT, RESISTOR, PASSIVE"
				(at 0 0 0)
				(effects
					(font
						(size 1.27 1.27)
					)
					(hide yes)
				)
			)
			(symbol "R_100R_0402_0_1"
				(rectangle
					(start 0.635 0.889)
					(end 4.445 -0.889)
					(stroke
						(width 0.254)
						(type default)
					)
					(fill
						(type none)
					)
				)
			)
			(symbol "R_100R_0402_1_1"
				(pin passive line
					(at 0 0 0)
					(length 0.635)
					(name "~"
						(effects
							(font
								(size 1.27 1.27)
							)
						)
					)
					(number "1"
						(effects
							(font
								(size 1.27 1.27)
							)
						)
					)
				)
				(pin passive line
					(at 5.08 0 180)
					(length 0.635)
					(name "~"
						(effects
							(font
								(size 1.27 1.27)
							)
						)
					)
					(number "2"
						(effects
							(font
								(size 1.27 1.27)
							)
						)
					)
				)
			)
		)
	(symbol "antmicroResistors0402:R_100k_0402"
			(pin_numbers hide)
			(pin_names hide)
			(exclude_from_sim no)
			(in_bom yes)
			(on_board yes)
			(property "Reference" "R"
				(at 20.32 -5.08 0)
				(effects
					(font
						(size 1.27 1.27)
						(thickness 0.15)
					)
					(justify left bottom)
				)
			)
			(property "Value" "R_100k_0402"
				(at 20.32 -12.7 0)
				(effects
					(font
						(size 1.27 1.27)
						(thickness 0.15)
					)
					(justify left bottom)
					(hide yes)
				)
			)
			(property "Footprint" "antmicro-footprints:R_0402_1005Metric"
				(at 20.32 -15.24 0)
				(effects
					(font
						(size 1.27 1.27)
						(thickness 0.15)
					)
					(justify left bottom)
					(hide yes)
				)
			)
			(property "Datasheet" "https://www.bourns.com/docs/product-datasheets/cr.pdf"
				(at 20.32 -17.78 0)
				(effects
					(font
						(size 1.27 1.27)
						(thickness 0.15)
					)
					(justify left bottom)
					(hide yes)
				)
			)
			(property "Description" "SMD Chip Resistor, 100 kohm, ± 1%, 62.5 mW, 0402 [1005 Metric], Thick Film, General Purpose"
				(at 0 0 0)
				(effects
					(font
						(size 1.27 1.27)
					)
					(hide yes)
				)
			)
			(property "MPN" "CR0402-FX-1003GLF"
				(at 20.32 -20.32 0)
				(effects
					(font
						(size 1.27 1.27)
						(thickness 0.15)
					)
					(justify left bottom)
					(hide yes)
				)
			)
			(property "Manufacturer" "Bourns"
				(at 20.32 -22.86 0)
				(effects
					(font
						(size 1.27 1.27)
						(thickness 0.15)
					)
					(justify left bottom)
					(hide yes)
				)
			)
			(property "License" "Apache-2.0"
				(at 20.32 -25.4 0)
				(effects
					(font
						(size 1.27 1.27)
						(thickness 0.15)
					)
					(justify left bottom)
					(hide yes)
				)
			)
			(property "Author" "Antmicro"
				(at 20.32 -27.94 0)
				(effects
					(font
						(size 1.27 1.27)
						(thickness 0.15)
					)
					(justify left bottom)
					(hide yes)
				)
			)
			(property "Val" "100k"
				(at 20.32 -7.62 0)
				(effects
					(font
						(size 1.27 1.27)
						(thickness 0.15)
					)
					(justify left bottom)
				)
			)
			(property "Tolerance" "1%"
				(at 20.32 -10.16 0)
				(effects
					(font
						(size 1.27 1.27)
					)
					(justify left bottom)
					(hide yes)
				)
			)
			(property "ki_keywords" "0402, SMT, RESISTOR, PASSIVE"
				(at 0 0 0)
				(effects
					(font
						(size 1.27 1.27)
					)
					(hide yes)
				)
			)
			(symbol "R_100k_0402_0_1"
				(rectangle
					(start 0.635 0.889)
					(end 4.445 -0.889)
					(stroke
						(width 0.254)
						(type default)
					)
					(fill
						(type none)
					)
				)
			)
			(symbol "R_100k_0402_1_1"
				(pin passive line
					(at 0 0 0)
					(length 0.635)
					(name "~"
						(effects
							(font
								(size 1.27 1.27)
							)
						)
					)
					(number "1"
						(effects
							(font
								(size 1.27 1.27)
							)
						)
					)
				)
				(pin passive line
					(at 5.08 0 180)
					(length 0.635)
					(name "~"
						(effects
							(font
								(size 1.27 1.27)
							)
						)
					)
					(number "2"
						(effects
							(font
								(size 1.27 1.27)
							)
						)
					)
				)
			)
		)
	(symbol "antmicroResistors0402:R_10k_0402"
			(pin_numbers hide)
			(pin_names hide)
			(exclude_from_sim no)
			(in_bom yes)
			(on_board yes)
			(property "Reference" "R"
				(at 20.32 -5.08 0)
				(effects
					(font
						(size 1.27 1.27)
						(thickness 0.15)
					)
					(justify left bottom)
				)
			)
			(property "Value" "R_10k_0402"
				(at 20.32 -12.7 0)
				(effects
					(font
						(size 1.27 1.27)
						(thickness 0.15)
					)
					(justify left bottom)
					(hide yes)
				)
			)
			(property "Footprint" "antmicro-footprints:R_0402_1005Metric"
				(at 20.32 -15.24 0)
				(effects
					(font
						(size 1.27 1.27)
						(thickness 0.15)
					)
					(justify left bottom)
					(hide yes)
				)
			)
			(property "Datasheet" "https://www.bourns.com/docs/product-datasheets/cr.pdf"
				(at 20.32 -17.78 0)
				(effects
					(font
						(size 1.27 1.27)
						(thickness 0.15)
					)
					(justify left bottom)
					(hide yes)
				)
			)
			(property "Description" "SMD Chip Resistor, 10 kohm, ± 1%, 62.5 mW, 0402 [1005 Metric], Thick Film, General Purpose"
				(at 0 0 0)
				(effects
					(font
						(size 1.27 1.27)
					)
					(hide yes)
				)
			)
			(property "MPN" "CR0402-FX-1002GLF"
				(at 20.32 -20.32 0)
				(effects
					(font
						(size 1.27 1.27)
						(thickness 0.15)
					)
					(justify left bottom)
					(hide yes)
				)
			)
			(property "Manufacturer" "Bourns"
				(at 20.32 -22.86 0)
				(effects
					(font
						(size 1.27 1.27)
						(thickness 0.15)
					)
					(justify left bottom)
					(hide yes)
				)
			)
			(property "License" "Apache-2.0"
				(at 20.32 -25.4 0)
				(effects
					(font
						(size 1.27 1.27)
						(thickness 0.15)
					)
					(justify left bottom)
					(hide yes)
				)
			)
			(property "Author" "Antmicro"
				(at 20.32 -27.94 0)
				(effects
					(font
						(size 1.27 1.27)
						(thickness 0.15)
					)
					(justify left bottom)
					(hide yes)
				)
			)
			(property "Val" "10k"
				(at 20.32 -7.62 0)
				(effects
					(font
						(size 1.27 1.27)
						(thickness 0.15)
					)
					(justify left bottom)
				)
			)
			(property "Tolerance" "1%"
				(at 20.32 -10.16 0)
				(effects
					(font
						(size 1.27 1.27)
					)
					(justify left bottom)
					(hide yes)
				)
			)
			(property "ki_keywords" "0402, SMT, RESISTOR, PASSIVE"
				(at 0 0 0)
				(effects
					(font
						(size 1.27 1.27)
					)
					(hide yes)
				)
			)
			(symbol "R_10k_0402_0_1"
				(rectangle
					(start 0.635 0.889)
					(end 4.445 -0.889)
					(stroke
						(width 0.254)
						(type default)
					)
					(fill
						(type none)
					)
				)
			)
			(symbol "R_10k_0402_1_1"
				(pin passive line
					(at 0 0 0)
					(length 0.635)
					(name "~"
						(effects
							(font
								(size 1.27 1.27)
							)
						)
					)
					(number "1"
						(effects
							(font
								(size 1.27 1.27)
							)
						)
					)
				)
				(pin passive line
					(at 5.08 0 180)
					(length 0.635)
					(name "~"
						(effects
							(font
								(size 1.27 1.27)
							)
						)
					)
					(number "2"
						(effects
							(font
								(size 1.27 1.27)
							)
						)
					)
				)
			)
		)
	(symbol "antmicroResistors0402:R_12k4_0402"
			(pin_numbers hide)
			(pin_names hide)
			(exclude_from_sim no)
			(in_bom yes)
			(on_board yes)
			(property "Reference" "R"
				(at 20.32 -5.08 0)
				(effects
					(font
						(size 1.27 1.27)
						(thickness 0.15)
					)
					(justify left bottom)
				)
			)
			(property "Value" "R_12k4_0402"
				(at 20.32 -12.7 0)
				(effects
					(font
						(size 1.27 1.27)
						(thickness 0.15)
					)
					(justify left bottom)
					(hide yes)
				)
			)
			(property "Footprint" "antmicro-footprints:R_0402_1005Metric"
				(at 20.32 -15.24 0)
				(effects
					(font
						(size 1.27 1.27)
						(thickness 0.15)
					)
					(justify left bottom)
					(hide yes)
				)
			)
			(property "Datasheet" "https://www.bourns.com/docs/product-datasheets/cr.pdf"
				(at 20.32 -17.78 0)
				(effects
					(font
						(size 1.27 1.27)
						(thickness 0.15)
					)
					(justify left bottom)
					(hide yes)
				)
			)
			(property "Description" "SMD Chip Resistor, 12.4 kohm, ± 1%, 62.5 mW, 0402 [1005 Metric], Thick Film, General Purpose"
				(at 0 0 0)
				(effects
					(font
						(size 1.27 1.27)
					)
					(hide yes)
				)
			)
			(property "MPN" "CR0402-FX-1242GLF"
				(at 20.32 -20.32 0)
				(effects
					(font
						(size 1.27 1.27)
						(thickness 0.15)
					)
					(justify left bottom)
					(hide yes)
				)
			)
			(property "Manufacturer" "Bourns"
				(at 20.32 -22.86 0)
				(effects
					(font
						(size 1.27 1.27)
						(thickness 0.15)
					)
					(justify left bottom)
					(hide yes)
				)
			)
			(property "License" "Apache-2.0"
				(at 20.32 -25.4 0)
				(effects
					(font
						(size 1.27 1.27)
						(thickness 0.15)
					)
					(justify left bottom)
					(hide yes)
				)
			)
			(property "Author" "Antmicro"
				(at 20.32 -27.94 0)
				(effects
					(font
						(size 1.27 1.27)
						(thickness 0.15)
					)
					(justify left bottom)
					(hide yes)
				)
			)
			(property "Val" "12k4"
				(at 20.32 -7.62 0)
				(effects
					(font
						(size 1.27 1.27)
						(thickness 0.15)
					)
					(justify left bottom)
				)
			)
			(property "Tolerance" "1%"
				(at 20.32 -10.16 0)
				(effects
					(font
						(size 1.27 1.27)
					)
					(justify left bottom)
					(hide yes)
				)
			)
			(property "ki_keywords" "0402, SMT, RESISTOR, PASSIVE"
				(at 0 0 0)
				(effects
					(font
						(size 1.27 1.27)
					)
					(hide yes)
				)
			)
			(symbol "R_12k4_0402_0_1"
				(rectangle
					(start 0.635 0.889)
					(end 4.445 -0.889)
					(stroke
						(width 0.254)
						(type default)
					)
					(fill
						(type none)
					)
				)
			)
			(symbol "R_12k4_0402_1_1"
				(pin passive line
					(at 0 0 0)
					(length 0.635)
					(name "~"
						(effects
							(font
								(size 1.27 1.27)
							)
						)
					)
					(number "1"
						(effects
							(font
								(size 1.27 1.27)
							)
						)
					)
				)
				(pin passive line
					(at 5.08 0 180)
					(length 0.635)
					(name "~"
						(effects
							(font
								(size 1.27 1.27)
							)
						)
					)
					(number "2"
						(effects
							(font
								(size 1.27 1.27)
							)
						)
					)
				)
			)
		)
	(symbol "antmicroResistors0402:R_12k_0402"
			(pin_numbers hide)
			(pin_names hide)
			(exclude_from_sim no)
			(in_bom yes)
			(on_board yes)
			(property "Reference" "R"
				(at 20.32 -5.08 0)
				(effects
					(font
						(size 1.27 1.27)
						(thickness 0.15)
					)
					(justify left bottom)
				)
			)
			(property "Value" "R_12k_0402"
				(at 20.32 -12.7 0)
				(effects
					(font
						(size 1.27 1.27)
						(thickness 0.15)
					)
					(justify left bottom)
					(hide yes)
				)
			)
			(property "Footprint" "antmicro-footprints:R_0402_1005Metric"
				(at 20.32 -15.24 0)
				(effects
					(font
						(size 1.27 1.27)
						(thickness 0.15)
					)
					(justify left bottom)
					(hide yes)
				)
			)
			(property "Datasheet" "https://www.bourns.com/docs/product-datasheets/cr.pdf"
				(at 20.32 -17.78 0)
				(effects
					(font
						(size 1.27 1.27)
						(thickness 0.15)
					)
					(justify left bottom)
					(hide yes)
				)
			)
			(property "Description" "SMD Chip Resistor, 12 kohm, ± 1%, 62.5 mW, 0402 [1005 Metric], Thick Film, General Purpose"
				(at 0 0 0)
				(effects
					(font
						(size 1.27 1.27)
					)
					(hide yes)
				)
			)
			(property "MPN" "CR0402-FX-1202GLF"
				(at 20.32 -20.32 0)
				(effects
					(font
						(size 1.27 1.27)
						(thickness 0.15)
					)
					(justify left bottom)
					(hide yes)
				)
			)
			(property "Manufacturer" "Bourns"
				(at 20.32 -22.86 0)
				(effects
					(font
						(size 1.27 1.27)
						(thickness 0.15)
					)
					(justify left bottom)
					(hide yes)
				)
			)
			(property "License" "Apache-2.0"
				(at 20.32 -25.4 0)
				(effects
					(font
						(size 1.27 1.27)
						(thickness 0.15)
					)
					(justify left bottom)
					(hide yes)
				)
			)
			(property "Author" "Antmicro"
				(at 20.32 -27.94 0)
				(effects
					(font
						(size 1.27 1.27)
						(thickness 0.15)
					)
					(justify left bottom)
					(hide yes)
				)
			)
			(property "Val" "12k"
				(at 20.32 -7.62 0)
				(effects
					(font
						(size 1.27 1.27)
						(thickness 0.15)
					)
					(justify left bottom)
				)
			)
			(property "Tolerance" "1%"
				(at 20.32 -10.16 0)
				(effects
					(font
						(size 1.27 1.27)
					)
					(justify left bottom)
					(hide yes)
				)
			)
			(property "ki_keywords" "0402, SMT, RESISTOR, PASSIVE"
				(at 0 0 0)
				(effects
					(font
						(size 1.27 1.27)
					)
					(hide yes)
				)
			)
			(symbol "R_12k_0402_0_1"
				(rectangle
					(start 0.635 0.889)
					(end 4.445 -0.889)
					(stroke
						(width 0.254)
						(type default)
					)
					(fill
						(type none)
					)
				)
			)
			(symbol "R_12k_0402_1_1"
				(pin passive line
					(at 0 0 0)
					(length 0.635)
					(name "~"
						(effects
							(font
								(size 1.27 1.27)
							)
						)
					)
					(number "1"
						(effects
							(font
								(size 1.27 1.27)
							)
						)
					)
				)
				(pin passive line
					(at 5.08 0 180)
					(length 0.635)
					(name "~"
						(effects
							(font
								(size 1.27 1.27)
							)
						)
					)
					(number "2"
						(effects
							(font
								(size 1.27 1.27)
							)
						)
					)
				)
			)
		)
	(symbol "antmicroResistors0402:R_1k65_0402"
			(pin_numbers hide)
			(pin_names hide)
			(exclude_from_sim no)
			(in_bom yes)
			(on_board yes)
			(property "Reference" "R"
				(at 20.32 -5.08 0)
				(effects
					(font
						(size 1.27 1.27)
						(thickness 0.15)
					)
					(justify left bottom)
				)
			)
			(property "Value" "R_1k65_0402"
				(at 20.32 -12.7 0)
				(effects
					(font
						(size 1.27 1.27)
						(thickness 0.15)
					)
					(justify left bottom)
					(hide yes)
				)
			)
			(property "Footprint" "antmicro-footprints:R_0402_1005Metric"
				(at 20.32 -15.24 0)
				(effects
					(font
						(size 1.27 1.27)
						(thickness 0.15)
					)
					(justify left bottom)
					(hide yes)
				)
			)
			(property "Datasheet" "https://www.farnell.com/datasheets/3795017.pdf"
				(at 20.32 -17.78 0)
				(effects
					(font
						(size 1.27 1.27)
						(thickness 0.15)
					)
					(justify left bottom)
					(hide yes)
				)
			)
			(property "Description" "SMD Chip Resistor, 1.65 kohm, ± 1%, 63 mW, 0402 [1005 Metric], Thick Film, General Purpose"
				(at 0 0 0)
				(effects
					(font
						(size 1.27 1.27)
					)
					(hide yes)
				)
			)
			(property "MPN" "RC0402FR-071K65L"
				(at 20.32 -20.32 0)
				(effects
					(font
						(size 1.27 1.27)
						(thickness 0.15)
					)
					(justify left bottom)
					(hide yes)
				)
			)
			(property "Manufacturer" "YAGEO"
				(at 20.32 -22.86 0)
				(effects
					(font
						(size 1.27 1.27)
						(thickness 0.15)
					)
					(justify left bottom)
					(hide yes)
				)
			)
			(property "License" "Apache-2.0"
				(at 20.32 -25.4 0)
				(effects
					(font
						(size 1.27 1.27)
						(thickness 0.15)
					)
					(justify left bottom)
					(hide yes)
				)
			)
			(property "Author" "Antmicro"
				(at 20.32 -27.94 0)
				(effects
					(font
						(size 1.27 1.27)
						(thickness 0.15)
					)
					(justify left bottom)
					(hide yes)
				)
			)
			(property "Val" "1k65"
				(at 20.32 -7.62 0)
				(effects
					(font
						(size 1.27 1.27)
						(thickness 0.15)
					)
					(justify left bottom)
				)
			)
			(property "Tolerance" "1%"
				(at 20.32 -10.16 0)
				(effects
					(font
						(size 1.27 1.27)
					)
					(justify left bottom)
					(hide yes)
				)
			)
			(property "ki_keywords" "0402, SMT, RESISTOR, PASSIVE"
				(at 0 0 0)
				(effects
					(font
						(size 1.27 1.27)
					)
					(hide yes)
				)
			)
			(symbol "R_1k65_0402_0_1"
				(rectangle
					(start 0.635 0.889)
					(end 4.445 -0.889)
					(stroke
						(width 0.254)
						(type default)
					)
					(fill
						(type none)
					)
				)
			)
			(symbol "R_1k65_0402_1_1"
				(pin passive line
					(at 0 0 0)
					(length 0.635)
					(name "~"
						(effects
							(font
								(size 1.27 1.27)
							)
						)
					)
					(number "1"
						(effects
							(font
								(size 1.27 1.27)
							)
						)
					)
				)
				(pin passive line
					(at 5.08 0 180)
					(length 0.635)
					(name "~"
						(effects
							(font
								(size 1.27 1.27)
							)
						)
					)
					(number "2"
						(effects
							(font
								(size 1.27 1.27)
							)
						)
					)
				)
			)
		)
	(symbol "antmicroResistors0402:R_200R_0402"
			(pin_numbers hide)
			(pin_names hide)
			(exclude_from_sim no)
			(in_bom yes)
			(on_board yes)
			(property "Reference" "R"
				(at 20.32 -5.08 0)
				(effects
					(font
						(size 1.27 1.27)
						(thickness 0.15)
					)
					(justify left bottom)
				)
			)
			(property "Value" "R_200R_0402"
				(at 20.32 -12.7 0)
				(effects
					(font
						(size 1.27 1.27)
						(thickness 0.15)
					)
					(justify left bottom)
					(hide yes)
				)
			)
			(property "Footprint" "antmicro-footprints:R_0402_1005Metric"
				(at 20.32 -15.24 0)
				(effects
					(font
						(size 1.27 1.27)
						(thickness 0.15)
					)
					(justify left bottom)
					(hide yes)
				)
			)
			(property "Datasheet" "https://www.bourns.com/docs/product-datasheets/cr.pdf"
				(at 20.32 -17.78 0)
				(effects
					(font
						(size 1.27 1.27)
						(thickness 0.15)
					)
					(justify left bottom)
					(hide yes)
				)
			)
			(property "Description" "SMD Chip Resistor, 200 ohm, ± 1%, 62.5 mW, 0402 [1005 Metric], Thick Film, General Purpose"
				(at 0 0 0)
				(effects
					(font
						(size 1.27 1.27)
					)
					(hide yes)
				)
			)
			(property "MPN" "CR0402-FX-2000GLF"
				(at 20.32 -20.32 0)
				(effects
					(font
						(size 1.27 1.27)
						(thickness 0.15)
					)
					(justify left bottom)
					(hide yes)
				)
			)
			(property "Manufacturer" "Bourns"
				(at 20.32 -22.86 0)
				(effects
					(font
						(size 1.27 1.27)
						(thickness 0.15)
					)
					(justify left bottom)
					(hide yes)
				)
			)
			(property "License" "Apache-2.0"
				(at 20.32 -25.4 0)
				(effects
					(font
						(size 1.27 1.27)
						(thickness 0.15)
					)
					(justify left bottom)
					(hide yes)
				)
			)
			(property "Author" "Antmicro"
				(at 20.32 -27.94 0)
				(effects
					(font
						(size 1.27 1.27)
						(thickness 0.15)
					)
					(justify left bottom)
					(hide yes)
				)
			)
			(property "Val" "200R"
				(at 20.32 -7.62 0)
				(effects
					(font
						(size 1.27 1.27)
						(thickness 0.15)
					)
					(justify left bottom)
				)
			)
			(property "Tolerance" "1%"
				(at 20.32 -10.16 0)
				(effects
					(font
						(size 1.27 1.27)
					)
					(justify left bottom)
					(hide yes)
				)
			)
			(property "ki_keywords" "0402, SMT, RESISTOR, PASSIVE"
				(at 0 0 0)
				(effects
					(font
						(size 1.27 1.27)
					)
					(hide yes)
				)
			)
			(symbol "R_200R_0402_0_1"
				(rectangle
					(start 0.635 0.889)
					(end 4.445 -0.889)
					(stroke
						(width 0.254)
						(type default)
					)
					(fill
						(type none)
					)
				)
			)
			(symbol "R_200R_0402_1_1"
				(pin passive line
					(at 0 0 0)
					(length 0.635)
					(name "~"
						(effects
							(font
								(size 1.27 1.27)
							)
						)
					)
					(number "1"
						(effects
							(font
								(size 1.27 1.27)
							)
						)
					)
				)
				(pin passive line
					(at 5.08 0 180)
					(length 0.635)
					(name "~"
						(effects
							(font
								(size 1.27 1.27)
							)
						)
					)
					(number "2"
						(effects
							(font
								(size 1.27 1.27)
							)
						)
					)
				)
			)
		)
	(symbol "antmicroResistors0402:R_31k6_0402"
			(pin_numbers hide)
			(pin_names hide)
			(exclude_from_sim no)
			(in_bom yes)
			(on_board yes)
			(property "Reference" "R"
				(at 20.32 -5.08 0)
				(effects
					(font
						(size 1.27 1.27)
						(thickness 0.15)
					)
					(justify left bottom)
				)
			)
			(property "Value" "R_31k6_0402"
				(at 20.32 -12.7 0)
				(effects
					(font
						(size 1.27 1.27)
						(thickness 0.15)
					)
					(justify left bottom)
					(hide yes)
				)
			)
			(property "Footprint" "antmicro-footprints:R_0402_1005Metric"
				(at 20.32 -15.24 0)
				(effects
					(font
						(size 1.27 1.27)
						(thickness 0.15)
					)
					(justify left bottom)
					(hide yes)
				)
			)
			(property "Datasheet" "https://www.bourns.com/docs/product-datasheets/cr.pdf"
				(at 20.32 -17.78 0)
				(effects
					(font
						(size 1.27 1.27)
						(thickness 0.15)
					)
					(justify left bottom)
					(hide yes)
				)
			)
			(property "Description" "SMD Chip Resistor"
				(at 0 0 0)
				(effects
					(font
						(size 1.27 1.27)
					)
					(hide yes)
				)
			)
			(property "MPN" "CR0402-FX-3162GLF"
				(at 20.32 -20.32 0)
				(effects
					(font
						(size 1.27 1.27)
						(thickness 0.15)
					)
					(justify left bottom)
					(hide yes)
				)
			)
			(property "Manufacturer" "Bourns"
				(at 20.32 -22.86 0)
				(effects
					(font
						(size 1.27 1.27)
						(thickness 0.15)
					)
					(justify left bottom)
					(hide yes)
				)
			)
			(property "License" "Apache-2.0"
				(at 20.32 -25.4 0)
				(effects
					(font
						(size 1.27 1.27)
						(thickness 0.15)
					)
					(justify left bottom)
					(hide yes)
				)
			)
			(property "Author" "Antmicro"
				(at 20.32 -27.94 0)
				(effects
					(font
						(size 1.27 1.27)
						(thickness 0.15)
					)
					(justify left bottom)
					(hide yes)
				)
			)
			(property "Val" "31k6"
				(at 20.32 -7.62 0)
				(effects
					(font
						(size 1.27 1.27)
						(thickness 0.15)
					)
					(justify left bottom)
				)
			)
			(property "Tolerance" "1%"
				(at 20.32 -10.16 0)
				(effects
					(font
						(size 1.27 1.27)
					)
					(justify left bottom)
					(hide yes)
				)
			)
			(property "ki_keywords" "0402, SMT, RESISTOR, PASSIVE"
				(at 0 0 0)
				(effects
					(font
						(size 1.27 1.27)
					)
					(hide yes)
				)
			)
			(symbol "R_31k6_0402_0_1"
				(rectangle
					(start 0.635 0.889)
					(end 4.445 -0.889)
					(stroke
						(width 0.254)
						(type default)
					)
					(fill
						(type none)
					)
				)
			)
			(symbol "R_31k6_0402_1_1"
				(pin passive line
					(at 0 0 0)
					(length 0.635)
					(name "~"
						(effects
							(font
								(size 1.27 1.27)
							)
						)
					)
					(number "1"
						(effects
							(font
								(size 1.27 1.27)
							)
						)
					)
				)
				(pin passive line
					(at 5.08 0 180)
					(length 0.635)
					(name "~"
						(effects
							(font
								(size 1.27 1.27)
							)
						)
					)
					(number "2"
						(effects
							(font
								(size 1.27 1.27)
							)
						)
					)
				)
			)
		)
	(symbol "antmicroResistors0402:R_402R_0402"
			(pin_numbers hide)
			(pin_names hide)
			(exclude_from_sim no)
			(in_bom yes)
			(on_board yes)
			(property "Reference" "R"
				(at 20.32 -5.08 0)
				(effects
					(font
						(size 1.27 1.27)
						(thickness 0.15)
					)
					(justify left bottom)
				)
			)
			(property "Value" "R_402R_0402"
				(at 20.32 -12.7 0)
				(effects
					(font
						(size 1.27 1.27)
						(thickness 0.15)
					)
					(justify left bottom)
					(hide yes)
				)
			)
			(property "Footprint" "antmicro-footprints:R_0402_1005Metric"
				(at 20.32 -15.24 0)
				(effects
					(font
						(size 1.27 1.27)
						(thickness 0.15)
					)
					(justify left bottom)
					(hide yes)
				)
			)
			(property "Datasheet" "https://www.mouser.com/datasheet/2/54/cr-1858361.pdf"
				(at 20.32 -17.78 0)
				(effects
					(font
						(size 1.27 1.27)
						(thickness 0.15)
					)
					(justify left bottom)
					(hide yes)
				)
			)
			(property "Description" "SMD Chip Resistor, 402 ohm, ± 1%, 63 mW, 0402 [1005 Metric], Thick Film, General Purpose"
				(at 0 0 0)
				(effects
					(font
						(size 1.27 1.27)
					)
					(hide yes)
				)
			)
			(property "MPN" "CR0402-FX-4020GLF"
				(at 20.32 -20.32 0)
				(effects
					(font
						(size 1.27 1.27)
						(thickness 0.15)
					)
					(justify left bottom)
					(hide yes)
				)
			)
			(property "Manufacturer" "Bourns"
				(at 20.32 -22.86 0)
				(effects
					(font
						(size 1.27 1.27)
						(thickness 0.15)
					)
					(justify left bottom)
					(hide yes)
				)
			)
			(property "License" "Apache-2.0"
				(at 20.32 -25.4 0)
				(effects
					(font
						(size 1.27 1.27)
						(thickness 0.15)
					)
					(justify left bottom)
					(hide yes)
				)
			)
			(property "Author" "Antmicro"
				(at 20.32 -27.94 0)
				(effects
					(font
						(size 1.27 1.27)
						(thickness 0.15)
					)
					(justify left bottom)
					(hide yes)
				)
			)
			(property "Val" "402R"
				(at 20.32 -7.62 0)
				(effects
					(font
						(size 1.27 1.27)
						(thickness 0.15)
					)
					(justify left bottom)
				)
			)
			(property "Tolerance" "1%"
				(at 20.32 -10.16 0)
				(effects
					(font
						(size 1.27 1.27)
					)
					(justify left bottom)
					(hide yes)
				)
			)
			(property "ki_keywords" "0402, SMT, RESISTOR, PASSIVE"
				(at 0 0 0)
				(effects
					(font
						(size 1.27 1.27)
					)
					(hide yes)
				)
			)
			(symbol "R_402R_0402_0_1"
				(rectangle
					(start 0.635 0.889)
					(end 4.445 -0.889)
					(stroke
						(width 0.254)
						(type default)
					)
					(fill
						(type none)
					)
				)
			)
			(symbol "R_402R_0402_1_1"
				(pin passive line
					(at 0 0 0)
					(length 0.635)
					(name "~"
						(effects
							(font
								(size 1.27 1.27)
							)
						)
					)
					(number "1"
						(effects
							(font
								(size 1.27 1.27)
							)
						)
					)
				)
				(pin passive line
					(at 5.08 0 180)
					(length 0.635)
					(name "~"
						(effects
							(font
								(size 1.27 1.27)
							)
						)
					)
					(number "2"
						(effects
							(font
								(size 1.27 1.27)
							)
						)
					)
				)
			)
		)
	(symbol "antmicroResistors0402:R_470R_0402"
			(pin_numbers hide)
			(pin_names hide)
			(exclude_from_sim no)
			(in_bom yes)
			(on_board yes)
			(property "Reference" "R"
				(at 20.32 -5.08 0)
				(effects
					(font
						(size 1.27 1.27)
						(thickness 0.15)
					)
					(justify left bottom)
				)
			)
			(property "Value" "R_470R_0402"
				(at 20.32 -12.7 0)
				(effects
					(font
						(size 1.27 1.27)
						(thickness 0.15)
					)
					(justify left bottom)
					(hide yes)
				)
			)
			(property "Footprint" "antmicro-footprints:R_0402_1005Metric"
				(at 20.32 -15.24 0)
				(effects
					(font
						(size 1.27 1.27)
						(thickness 0.15)
					)
					(justify left bottom)
					(hide yes)
				)
			)
			(property "Datasheet" "https://www.bourns.com/docs/product-datasheets/cr.pdf"
				(at 20.32 -17.78 0)
				(effects
					(font
						(size 1.27 1.27)
						(thickness 0.15)
					)
					(justify left bottom)
					(hide yes)
				)
			)
			(property "Description" "SMD Chip Resistor, 470 ohm, ± 1%, 62.5 mW, 0402 [1005 Metric], Thick Film, General Purpose"
				(at 0 0 0)
				(effects
					(font
						(size 1.27 1.27)
					)
					(hide yes)
				)
			)
			(property "MPN" "CR0402-FX-4700GLF"
				(at 20.32 -20.32 0)
				(effects
					(font
						(size 1.27 1.27)
						(thickness 0.15)
					)
					(justify left bottom)
					(hide yes)
				)
			)
			(property "Manufacturer" "Bourns"
				(at 20.32 -22.86 0)
				(effects
					(font
						(size 1.27 1.27)
						(thickness 0.15)
					)
					(justify left bottom)
					(hide yes)
				)
			)
			(property "License" "Apache-2.0"
				(at 20.32 -25.4 0)
				(effects
					(font
						(size 1.27 1.27)
						(thickness 0.15)
					)
					(justify left bottom)
					(hide yes)
				)
			)
			(property "Author" "Antmicro"
				(at 20.32 -27.94 0)
				(effects
					(font
						(size 1.27 1.27)
						(thickness 0.15)
					)
					(justify left bottom)
					(hide yes)
				)
			)
			(property "Val" "470R"
				(at 20.32 -7.62 0)
				(effects
					(font
						(size 1.27 1.27)
						(thickness 0.15)
					)
					(justify left bottom)
				)
			)
			(property "Tolerance" "1%"
				(at 20.32 -10.16 0)
				(effects
					(font
						(size 1.27 1.27)
					)
					(justify left bottom)
					(hide yes)
				)
			)
			(property "ki_keywords" "0402, SMT, RESISTOR, PASSIVE"
				(at 0 0 0)
				(effects
					(font
						(size 1.27 1.27)
					)
					(hide yes)
				)
			)
			(symbol "R_470R_0402_0_1"
				(rectangle
					(start 0.635 0.889)
					(end 4.445 -0.889)
					(stroke
						(width 0.254)
						(type default)
					)
					(fill
						(type none)
					)
				)
			)
			(symbol "R_470R_0402_1_1"
				(pin passive line
					(at 0 0 0)
					(length 0.635)
					(name "~"
						(effects
							(font
								(size 1.27 1.27)
							)
						)
					)
					(number "1"
						(effects
							(font
								(size 1.27 1.27)
							)
						)
					)
				)
				(pin passive line
					(at 5.08 0 180)
					(length 0.635)
					(name "~"
						(effects
							(font
								(size 1.27 1.27)
							)
						)
					)
					(number "2"
						(effects
							(font
								(size 1.27 1.27)
							)
						)
					)
				)
			)
		)
	(symbol "antmicroResistors0402:R_4k7_0402"
			(pin_numbers hide)
			(pin_names hide)
			(exclude_from_sim no)
			(in_bom yes)
			(on_board yes)
			(property "Reference" "R"
				(at 20.32 -5.08 0)
				(effects
					(font
						(size 1.27 1.27)
						(thickness 0.15)
					)
					(justify left bottom)
				)
			)
			(property "Value" "R_4k7_0402"
				(at 20.32 -12.7 0)
				(effects
					(font
						(size 1.27 1.27)
						(thickness 0.15)
					)
					(justify left bottom)
					(hide yes)
				)
			)
			(property "Footprint" "antmicro-footprints:R_0402_1005Metric"
				(at 20.32 -15.24 0)
				(effects
					(font
						(size 1.27 1.27)
						(thickness 0.15)
					)
					(justify left bottom)
					(hide yes)
				)
			)
			(property "Datasheet" "https://www.bourns.com/docs/product-datasheets/cr.pdf"
				(at 20.32 -17.78 0)
				(effects
					(font
						(size 1.27 1.27)
						(thickness 0.15)
					)
					(justify left bottom)
					(hide yes)
				)
			)
			(property "Description" "SMD Chip Resistor, 4.7 kohm, ± 1%, 62.5 mW, 0402 [1005 Metric], Thick Film, General Purpose"
				(at 0 0 0)
				(effects
					(font
						(size 1.27 1.27)
					)
					(hide yes)
				)
			)
			(property "MPN" "CR0402-FX-4701GLF"
				(at 20.32 -20.32 0)
				(effects
					(font
						(size 1.27 1.27)
						(thickness 0.15)
					)
					(justify left bottom)
					(hide yes)
				)
			)
			(property "Manufacturer" "Bourns"
				(at 20.32 -22.86 0)
				(effects
					(font
						(size 1.27 1.27)
						(thickness 0.15)
					)
					(justify left bottom)
					(hide yes)
				)
			)
			(property "License" "Apache-2.0"
				(at 20.32 -25.4 0)
				(effects
					(font
						(size 1.27 1.27)
						(thickness 0.15)
					)
					(justify left bottom)
					(hide yes)
				)
			)
			(property "Author" "Antmicro"
				(at 20.32 -27.94 0)
				(effects
					(font
						(size 1.27 1.27)
						(thickness 0.15)
					)
					(justify left bottom)
					(hide yes)
				)
			)
			(property "Val" "4k7"
				(at 20.32 -7.62 0)
				(effects
					(font
						(size 1.27 1.27)
						(thickness 0.15)
					)
					(justify left bottom)
				)
			)
			(property "Tolerance" "1%"
				(at 20.32 -10.16 0)
				(effects
					(font
						(size 1.27 1.27)
					)
					(justify left bottom)
					(hide yes)
				)
			)
			(property "ki_keywords" "0402, SMT, RESISTOR, PASSIVE"
				(at 0 0 0)
				(effects
					(font
						(size 1.27 1.27)
					)
					(hide yes)
				)
			)
			(symbol "R_4k7_0402_0_1"
				(rectangle
					(start 0.635 0.889)
					(end 4.445 -0.889)
					(stroke
						(width 0.254)
						(type default)
					)
					(fill
						(type none)
					)
				)
			)
			(symbol "R_4k7_0402_1_1"
				(pin passive line
					(at 0 0 0)
					(length 0.635)
					(name "~"
						(effects
							(font
								(size 1.27 1.27)
							)
						)
					)
					(number "1"
						(effects
							(font
								(size 1.27 1.27)
							)
						)
					)
				)
				(pin passive line
					(at 5.08 0 180)
					(length 0.635)
					(name "~"
						(effects
							(font
								(size 1.27 1.27)
							)
						)
					)
					(number "2"
						(effects
							(font
								(size 1.27 1.27)
							)
						)
					)
				)
			)
		)
	(symbol "antmicroResistors0402:R_51R_0402"
			(pin_numbers hide)
			(pin_names hide)
			(exclude_from_sim no)
			(in_bom yes)
			(on_board yes)
			(property "Reference" "R"
				(at 20.32 -5.08 0)
				(effects
					(font
						(size 1.27 1.27)
						(thickness 0.15)
					)
					(justify left bottom)
				)
			)
			(property "Value" "R_51R_0402"
				(at 20.32 -12.7 0)
				(effects
					(font
						(size 1.27 1.27)
						(thickness 0.15)
					)
					(justify left bottom)
					(hide yes)
				)
			)
			(property "Footprint" "antmicro-footprints:R_0402_1005Metric"
				(at 20.32 -15.24 0)
				(effects
					(font
						(size 1.27 1.27)
						(thickness 0.15)
					)
					(justify left bottom)
					(hide yes)
				)
			)
			(property "Datasheet" "https://www.bourns.com/docs/product-datasheets/cr.pdf"
				(at 20.32 -17.78 0)
				(effects
					(font
						(size 1.27 1.27)
						(thickness 0.15)
					)
					(justify left bottom)
					(hide yes)
				)
			)
			(property "Description" "SMD Chip Resistor, 51 ohm, ± 1%, 63 mW, 0402 [1005 Metric], Thick Film, General Purpose"
				(at 0 0 0)
				(effects
					(font
						(size 1.27 1.27)
					)
					(hide yes)
				)
			)
			(property "MPN" "CR0402-FX-51R0GLF"
				(at 20.32 -20.32 0)
				(effects
					(font
						(size 1.27 1.27)
						(thickness 0.15)
					)
					(justify left bottom)
					(hide yes)
				)
			)
			(property "Manufacturer" "Bourns"
				(at 20.32 -22.86 0)
				(effects
					(font
						(size 1.27 1.27)
						(thickness 0.15)
					)
					(justify left bottom)
					(hide yes)
				)
			)
			(property "License" "Apache-2.0"
				(at 20.32 -25.4 0)
				(effects
					(font
						(size 1.27 1.27)
						(thickness 0.15)
					)
					(justify left bottom)
					(hide yes)
				)
			)
			(property "Author" "Antmicro"
				(at 20.32 -27.94 0)
				(effects
					(font
						(size 1.27 1.27)
						(thickness 0.15)
					)
					(justify left bottom)
					(hide yes)
				)
			)
			(property "Val" "51R"
				(at 20.32 -7.62 0)
				(effects
					(font
						(size 1.27 1.27)
						(thickness 0.15)
					)
					(justify left bottom)
				)
			)
			(property "Tolerance" "1%"
				(at 20.32 -10.16 0)
				(effects
					(font
						(size 1.27 1.27)
					)
					(justify left bottom)
					(hide yes)
				)
			)
			(property "ki_keywords" "0402, SMT, RESISTOR, PASSIVE"
				(at 0 0 0)
				(effects
					(font
						(size 1.27 1.27)
					)
					(hide yes)
				)
			)
			(symbol "R_51R_0402_0_1"
				(rectangle
					(start 0.635 0.889)
					(end 4.445 -0.889)
					(stroke
						(width 0.254)
						(type default)
					)
					(fill
						(type none)
					)
				)
			)
			(symbol "R_51R_0402_1_1"
				(pin passive line
					(at 0 0 0)
					(length 0.635)
					(name "~"
						(effects
							(font
								(size 1.27 1.27)
							)
						)
					)
					(number "1"
						(effects
							(font
								(size 1.27 1.27)
							)
						)
					)
				)
				(pin passive line
					(at 5.08 0 180)
					(length 0.635)
					(name "~"
						(effects
							(font
								(size 1.27 1.27)
							)
						)
					)
					(number "2"
						(effects
							(font
								(size 1.27 1.27)
							)
						)
					)
				)
			)
		)
	(symbol "antmicroResistors0402:R_52k3_0402"
			(pin_numbers hide)
			(pin_names hide)
			(exclude_from_sim no)
			(in_bom yes)
			(on_board yes)
			(property "Reference" "R"
				(at 20.32 -5.08 0)
				(effects
					(font
						(size 1.27 1.27)
						(thickness 0.15)
					)
					(justify left bottom)
				)
			)
			(property "Value" "R_52k3_0402"
				(at 20.32 -12.7 0)
				(effects
					(font
						(size 1.27 1.27)
						(thickness 0.15)
					)
					(justify left bottom)
					(hide yes)
				)
			)
			(property "Footprint" "antmicro-footprints:R_0402_1005Metric"
				(at 20.32 -15.24 0)
				(effects
					(font
						(size 1.27 1.27)
						(thickness 0.15)
					)
					(justify left bottom)
					(hide yes)
				)
			)
			(property "Datasheet" "https://www.bourns.com/docs/product-datasheets/cr.pdf"
				(at 20.32 -17.78 0)
				(effects
					(font
						(size 1.27 1.27)
						(thickness 0.15)
					)
					(justify left bottom)
					(hide yes)
				)
			)
			(property "Description" "SMD Chip Resistor, 52.3 kohm, ± 1%, 63 mW, 0402 [1005 Metric], Thick Film, General Purpose"
				(at 0 0 0)
				(effects
					(font
						(size 1.27 1.27)
					)
					(hide yes)
				)
			)
			(property "MPN" "CR0402-FX-5232GLF"
				(at 20.32 -20.32 0)
				(effects
					(font
						(size 1.27 1.27)
						(thickness 0.15)
					)
					(justify left bottom)
					(hide yes)
				)
			)
			(property "Manufacturer" "Bourns"
				(at 20.32 -22.86 0)
				(effects
					(font
						(size 1.27 1.27)
						(thickness 0.15)
					)
					(justify left bottom)
					(hide yes)
				)
			)
			(property "License" "Apache-2.0"
				(at 20.32 -25.4 0)
				(effects
					(font
						(size 1.27 1.27)
						(thickness 0.15)
					)
					(justify left bottom)
					(hide yes)
				)
			)
			(property "Author" "Antmicro"
				(at 20.32 -27.94 0)
				(effects
					(font
						(size 1.27 1.27)
						(thickness 0.15)
					)
					(justify left bottom)
					(hide yes)
				)
			)
			(property "Val" "52k3"
				(at 20.32 -7.62 0)
				(effects
					(font
						(size 1.27 1.27)
						(thickness 0.15)
					)
					(justify left bottom)
				)
			)
			(property "Tolerance" "1%"
				(at 20.32 -10.16 0)
				(effects
					(font
						(size 1.27 1.27)
					)
					(justify left bottom)
					(hide yes)
				)
			)
			(property "ki_keywords" "0402, SMT, RESISTOR, PASSIVE"
				(at 0 0 0)
				(effects
					(font
						(size 1.27 1.27)
					)
					(hide yes)
				)
			)
			(symbol "R_52k3_0402_0_1"
				(rectangle
					(start 0.635 0.889)
					(end 4.445 -0.889)
					(stroke
						(width 0.254)
						(type default)
					)
					(fill
						(type none)
					)
				)
			)
			(symbol "R_52k3_0402_1_1"
				(pin passive line
					(at 0 0 0)
					(length 0.635)
					(name "~"
						(effects
							(font
								(size 1.27 1.27)
							)
						)
					)
					(number "1"
						(effects
							(font
								(size 1.27 1.27)
							)
						)
					)
				)
				(pin passive line
					(at 5.08 0 180)
					(length 0.635)
					(name "~"
						(effects
							(font
								(size 1.27 1.27)
							)
						)
					)
					(number "2"
						(effects
							(font
								(size 1.27 1.27)
							)
						)
					)
				)
			)
		)
	(symbol "antmicroResistors0402:R_5k1_0402"
			(pin_numbers hide)
			(pin_names hide)
			(exclude_from_sim no)
			(in_bom yes)
			(on_board yes)
			(property "Reference" "R"
				(at 20.32 -5.08 0)
				(effects
					(font
						(size 1.27 1.27)
						(thickness 0.15)
					)
					(justify left bottom)
				)
			)
			(property "Value" "R_5k1_0402"
				(at 20.32 -12.7 0)
				(effects
					(font
						(size 1.27 1.27)
						(thickness 0.15)
					)
					(justify left bottom)
					(hide yes)
				)
			)
			(property "Footprint" "antmicro-footprints:R_0402_1005Metric"
				(at 20.32 -15.24 0)
				(effects
					(font
						(size 1.27 1.27)
						(thickness 0.15)
					)
					(justify left bottom)
					(hide yes)
				)
			)
			(property "Datasheet" "https://www.bourns.com/docs/product-datasheets/cr.pdf"
				(at 20.32 -17.78 0)
				(effects
					(font
						(size 1.27 1.27)
						(thickness 0.15)
					)
					(justify left bottom)
					(hide yes)
				)
			)
			(property "Description" "SMD Chip Resistor, 5.1 kohm, ± 1%, 63 mW, 0402 [1005 Metric], Thick Film, General Purpose"
				(at 0 0 0)
				(effects
					(font
						(size 1.27 1.27)
					)
					(hide yes)
				)
			)
			(property "MPN" "CR0402-FX-5101GLF"
				(at 20.32 -20.32 0)
				(effects
					(font
						(size 1.27 1.27)
						(thickness 0.15)
					)
					(justify left bottom)
					(hide yes)
				)
			)
			(property "Manufacturer" "Bourns"
				(at 20.32 -22.86 0)
				(effects
					(font
						(size 1.27 1.27)
						(thickness 0.15)
					)
					(justify left bottom)
					(hide yes)
				)
			)
			(property "License" "Apache-2.0"
				(at 20.32 -25.4 0)
				(effects
					(font
						(size 1.27 1.27)
						(thickness 0.15)
					)
					(justify left bottom)
					(hide yes)
				)
			)
			(property "Author" "Antmicro"
				(at 20.32 -27.94 0)
				(effects
					(font
						(size 1.27 1.27)
						(thickness 0.15)
					)
					(justify left bottom)
					(hide yes)
				)
			)
			(property "Val" "5k1"
				(at 20.32 -7.62 0)
				(effects
					(font
						(size 1.27 1.27)
						(thickness 0.15)
					)
					(justify left bottom)
				)
			)
			(property "Tolerance" "1%"
				(at 20.32 -10.16 0)
				(effects
					(font
						(size 1.27 1.27)
					)
					(justify left bottom)
					(hide yes)
				)
			)
			(property "ki_keywords" "0402, SMT, RESISTOR, PASSIVE"
				(at 0 0 0)
				(effects
					(font
						(size 1.27 1.27)
					)
					(hide yes)
				)
			)
			(symbol "R_5k1_0402_0_1"
				(rectangle
					(start 0.635 0.889)
					(end 4.445 -0.889)
					(stroke
						(width 0.254)
						(type default)
					)
					(fill
						(type none)
					)
				)
			)
			(symbol "R_5k1_0402_1_1"
				(pin passive line
					(at 0 0 0)
					(length 0.635)
					(name "~"
						(effects
							(font
								(size 1.27 1.27)
							)
						)
					)
					(number "1"
						(effects
							(font
								(size 1.27 1.27)
							)
						)
					)
				)
				(pin passive line
					(at 5.08 0 180)
					(length 0.635)
					(name "~"
						(effects
							(font
								(size 1.27 1.27)
							)
						)
					)
					(number "2"
						(effects
							(font
								(size 1.27 1.27)
							)
						)
					)
				)
			)
		)
	(symbol "antmicroResistors0402:R_80k6_0402"
			(pin_numbers hide)
			(pin_names hide)
			(exclude_from_sim no)
			(in_bom yes)
			(on_board yes)
			(property "Reference" "R"
				(at 20.32 -5.08 0)
				(effects
					(font
						(size 1.27 1.27)
						(thickness 0.15)
					)
					(justify left bottom)
				)
			)
			(property "Value" "R_80k6_0402"
				(at 20.32 -12.7 0)
				(effects
					(font
						(size 1.27 1.27)
						(thickness 0.15)
					)
					(justify left bottom)
					(hide yes)
				)
			)
			(property "Footprint" "antmicro-footprints:R_0402_1005Metric"
				(at 20.32 -15.24 0)
				(effects
					(font
						(size 1.27 1.27)
						(thickness 0.15)
					)
					(justify left bottom)
					(hide yes)
				)
			)
			(property "Datasheet" "https://www.bourns.com/docs/product-datasheets/cr.pdf"
				(at 20.32 -17.78 0)
				(effects
					(font
						(size 1.27 1.27)
						(thickness 0.15)
					)
					(justify left bottom)
					(hide yes)
				)
			)
			(property "Description" "SMD Chip Resistor, 80.6 kohm, ± 1%, 100 mW, 0402 [1005 Metric], Thick Film, Precision"
				(at 0 0 0)
				(effects
					(font
						(size 1.27 1.27)
					)
					(hide yes)
				)
			)
			(property "MPN" "CR0402-FX-8062GLF"
				(at 20.32 -20.32 0)
				(effects
					(font
						(size 1.27 1.27)
						(thickness 0.15)
					)
					(justify left bottom)
					(hide yes)
				)
			)
			(property "Manufacturer" "Bourns"
				(at 20.32 -22.86 0)
				(effects
					(font
						(size 1.27 1.27)
						(thickness 0.15)
					)
					(justify left bottom)
					(hide yes)
				)
			)
			(property "License" "Apache-2.0"
				(at 20.32 -25.4 0)
				(effects
					(font
						(size 1.27 1.27)
						(thickness 0.15)
					)
					(justify left bottom)
					(hide yes)
				)
			)
			(property "Author" "Antmicro"
				(at 20.32 -27.94 0)
				(effects
					(font
						(size 1.27 1.27)
						(thickness 0.15)
					)
					(justify left bottom)
					(hide yes)
				)
			)
			(property "Val" "80k6"
				(at 20.32 -7.62 0)
				(effects
					(font
						(size 1.27 1.27)
						(thickness 0.15)
					)
					(justify left bottom)
				)
			)
			(property "Tolerance" "1%"
				(at 20.32 -10.16 0)
				(effects
					(font
						(size 1.27 1.27)
					)
					(justify left bottom)
					(hide yes)
				)
			)
			(property "ki_keywords" "0402, SMT, RESISTOR, PASSIVE"
				(at 0 0 0)
				(effects
					(font
						(size 1.27 1.27)
					)
					(hide yes)
				)
			)
			(symbol "R_80k6_0402_0_1"
				(rectangle
					(start 0.635 0.889)
					(end 4.445 -0.889)
					(stroke
						(width 0.254)
						(type default)
					)
					(fill
						(type none)
					)
				)
			)
			(symbol "R_80k6_0402_1_1"
				(pin passive line
					(at 0 0 0)
					(length 0.635)
					(name "~"
						(effects
							(font
								(size 1.27 1.27)
							)
						)
					)
					(number "1"
						(effects
							(font
								(size 1.27 1.27)
							)
						)
					)
				)
				(pin passive line
					(at 5.08 0 180)
					(length 0.635)
					(name "~"
						(effects
							(font
								(size 1.27 1.27)
							)
						)
					)
					(number "2"
						(effects
							(font
								(size 1.27 1.27)
							)
						)
					)
				)
			)
		)
	(symbol "antmicroResistors0603:R_0R_22.4A_0603"
			(pin_numbers hide)
			(pin_names hide)
			(exclude_from_sim no)
			(in_bom yes)
			(on_board yes)
			(property "Reference" "R"
				(at 15.24 -2.54 0)
				(effects
					(font
						(size 1.27 1.27)
						(thickness 0.15)
					)
					(justify left bottom)
				)
			)
			(property "Value" "R_0R_22.4A_0603"
				(at 15.24 -5.08 0)
				(effects
					(font
						(size 1.27 1.27)
						(thickness 0.15)
					)
					(justify left bottom)
				)
			)
			(property "Footprint" "antmicro-footprints:R_0603_1608Metric"
				(at 15.24 -10.16 0)
				(effects
					(font
						(size 1.27 1.27)
						(thickness 0.15)
					)
					(justify left bottom)
					(hide yes)
				)
			)
			(property "Datasheet" "https://fscdn.rohm.com/en/products/databook/datasheet/passive/resistor/chip_resistor/pmr-jpw-e.pdf"
				(at 15.24 -12.7 0)
				(effects
					(font
						(size 1.27 1.27)
						(thickness 0.15)
					)
					(justify left bottom)
					(hide yes)
				)
			)
			(property "Description" "SMD Chip Resistor"
				(at 0 0 0)
				(effects
					(font
						(size 1.27 1.27)
					)
					(hide yes)
				)
			)
			(property "MPN" "PMR03EZPJ000"
				(at 15.24 -15.24 0)
				(effects
					(font
						(size 1.27 1.27)
						(thickness 0.15)
					)
					(justify left bottom)
					(hide yes)
				)
			)
			(property "Manufacturer" "ROHM Semiconductor"
				(at 15.24 -17.78 0)
				(effects
					(font
						(size 1.27 1.27)
						(thickness 0.15)
					)
					(justify left bottom)
					(hide yes)
				)
			)
			(property "Val" "0R"
				(at 15.24 -7.62 0)
				(effects
					(font
						(size 1.27 1.27)
						(thickness 0.15)
					)
					(justify left bottom)
				)
			)
			(property "Max. Curr." "22.4A"
				(at 15.24 -20.32 0)
				(effects
					(font
						(size 1.27 1.27)
						(thickness 0.15)
					)
					(justify left bottom)
				)
			)
			(property "Author" "Antmicro"
				(at 15.24 -22.86 0)
				(effects
					(font
						(size 1.27 1.27)
						(thickness 0.15)
					)
					(justify left bottom)
					(hide yes)
				)
			)
			(property "License" "Apache-2.0"
				(at 15.24 -25.4 0)
				(effects
					(font
						(size 1.27 1.27)
						(thickness 0.15)
					)
					(justify left bottom)
					(hide yes)
				)
			)
			(property "Tolerance" "template_tolerance"
				(at 20.32 -10.16 0)
				(effects
					(font
						(size 1.27 1.27)
					)
					(justify left bottom)
					(hide yes)
				)
			)
			(property "ki_keywords" "0603, SMT, RESISTOR, PASSIVE"
				(at 0 0 0)
				(effects
					(font
						(size 1.27 1.27)
					)
					(hide yes)
				)
			)
			(symbol "R_0R_22.4A_0603_0_1"
				(rectangle
					(start 0.635 0.889)
					(end 4.445 -0.889)
					(stroke
						(width 0.254)
						(type default)
					)
					(fill
						(type none)
					)
				)
			)
			(symbol "R_0R_22.4A_0603_1_1"
				(pin passive line
					(at 0 0 0)
					(length 0.635)
					(name "~"
						(effects
							(font
								(size 1.27 1.27)
							)
						)
					)
					(number "1"
						(effects
							(font
								(size 1.27 1.27)
							)
						)
					)
				)
				(pin passive line
					(at 5.08 0 180)
					(length 0.635)
					(name "~"
						(effects
							(font
								(size 1.27 1.27)
							)
						)
					)
					(number "2"
						(effects
							(font
								(size 1.27 1.27)
							)
						)
					)
				)
			)
		)
	(symbol "antmicroResonators:Resonator_25MHz_ABM8G"
			(pin_names hide)
			(exclude_from_sim no)
			(in_bom yes)
			(on_board yes)
			(property "Reference" "Y"
				(at 15.24 -5.08 0)
				(effects
					(font
						(size 1.27 1.27)
						(thickness 0.15)
					)
					(justify left bottom)
				)
			)
			(property "Value" "Resonator_25MHz_ABM8G"
				(at 15.24 -12.7 0)
				(effects
					(font
						(size 1.27 1.27)
						(thickness 0.15)
					)
					(justify left bottom)
					(hide yes)
				)
			)
			(property "Footprint" "antmicro-footprints:Resonator_SMD_Abracon_ABM8G_3.2x2.5mm"
				(at 15.24 -15.24 0)
				(effects
					(font
						(size 1.27 1.27)
						(thickness 0.15)
					)
					(justify left bottom)
					(hide yes)
				)
			)
			(property "Datasheet" "https://abracon.com/Resonators/ABM8G.pdf"
				(at 15.24 -17.78 0)
				(effects
					(font
						(size 1.27 1.27)
						(thickness 0.15)
					)
					(justify left bottom)
					(hide yes)
				)
			)
			(property "Description" "Crystal, 25 MHz, SMD, 3.2mm x 2.5mm, 30 ppm, 18 pF, 20 ppm, ABM8G"
				(at 0 0 0)
				(effects
					(font
						(size 1.27 1.27)
					)
					(hide yes)
				)
			)
			(property "MPN" "ABM8G-25.000MHZ-18-D2Y-T3"
				(at 15.24 -7.62 0)
				(effects
					(font
						(size 1.27 1.27)
						(thickness 0.15)
					)
					(justify left bottom)
				)
			)
			(property "Manufacturer" "Abracon"
				(at 15.24 -20.32 0)
				(effects
					(font
						(size 1.27 1.27)
						(thickness 0.15)
					)
					(justify left bottom)
					(hide yes)
				)
			)
			(property "Author" "Antmicro"
				(at 15.24 -22.86 0)
				(effects
					(font
						(size 1.27 1.27)
						(thickness 0.15)
					)
					(justify left bottom)
					(hide yes)
				)
			)
			(property "License" "Apache-2.0"
				(at 15.24 -25.4 0)
				(effects
					(font
						(size 1.27 1.27)
						(thickness 0.15)
					)
					(justify left bottom)
					(hide yes)
				)
			)
			(property "Val" "25 MHz"
				(at 15.24 -10.16 0)
				(effects
					(font
						(size 1.27 1.27)
						(thickness 0.15)
					)
					(justify left bottom)
				)
			)
			(property "ki_keywords" "SMT, CERAMIC, OSCILLATOR"
				(at 0 0 0)
				(effects
					(font
						(size 1.27 1.27)
					)
					(hide yes)
				)
			)
			(symbol "Resonator_25MHz_ABM8G_1_1"
				(polyline
					(pts
						(xy 2.54 1.27) (xy 2.54 -1.27)
					)
					(stroke
						(width 0.254)
						(type default)
					)
					(fill
						(type background)
					)
				)
				(polyline
					(pts
						(xy 5.08 1.27) (xy 5.08 -1.27)
					)
					(stroke
						(width 0.254)
						(type default)
					)
					(fill
						(type background)
					)
				)
				(polyline
					(pts
						(xy 1.905 -1.905) (xy 1.905 -2.54) (xy 5.715 -2.54) (xy 5.715 -1.905)
					)
					(stroke
						(width 0.254)
						(type default)
					)
					(fill
						(type none)
					)
				)
				(polyline
					(pts
						(xy 1.905 1.905) (xy 1.905 2.54) (xy 5.715 2.54) (xy 5.715 1.905)
					)
					(stroke
						(width 0.254)
						(type default)
					)
					(fill
						(type none)
					)
				)
				(rectangle
					(start 3.175 1.905)
					(end 4.445 -1.905)
					(stroke
						(width 0.254)
						(type default)
					)
					(fill
						(type background)
					)
				)
				(pin passive line
					(at 0 0 0)
					(length 2.54)
					(name "~"
						(effects
							(font
								(size 1.27 1.27)
							)
						)
					)
					(number "1"
						(effects
							(font
								(size 1.27 1.27)
							)
						)
					)
				)
				(pin passive line
					(at 3.81 -5.08 90)
					(length 2.54)
					(name "SH"
						(effects
							(font
								(size 1.27 1.27)
							)
						)
					)
					(number "2"
						(effects
							(font
								(size 1.27 1.27)
							)
						)
					)
				)
				(pin passive line
					(at 7.62 0 180)
					(length 2.54)
					(name "~"
						(effects
							(font
								(size 1.27 1.27)
							)
						)
					)
					(number "3"
						(effects
							(font
								(size 1.27 1.27)
							)
						)
					)
				)
				(pin passive line
					(at 3.81 -5.08 90)
					(length 2.54) hide
					(name "SH"
						(effects
							(font
								(size 1.27 1.27)
							)
						)
					)
					(number "4"
						(effects
							(font
								(size 1.27 1.27)
							)
						)
					)
				)
			)
		)
	(symbol "antmicroTVSDiodes:AXGD10402KR"
			(pin_numbers hide)
			(pin_names hide)
			(exclude_from_sim no)
			(in_bom yes)
			(on_board yes)
			(property "Reference" "D"
				(at 25.4 -5.08 0)
				(effects
					(font
						(size 1.27 1.27)
						(thickness 0.15)
					)
					(justify left bottom)
				)
			)
			(property "Value" "AXGD10402KR"
				(at 25.4 -10.16 0)
				(effects
					(font
						(size 1.27 1.27)
						(thickness 0.15)
					)
					(justify left bottom)
					(hide yes)
				)
			)
			(property "Footprint" "antmicro-footprints:D_0402_1005Metric"
				(at 25.4 -12.7 0)
				(effects
					(font
						(size 1.27 1.27)
						(thickness 0.15)
					)
					(justify left bottom)
					(hide yes)
				)
			)
			(property "Datasheet" "https://www.littelfuse.com/media?resourcetype=datasheets&itemid=020b2bf2-064c-4ff1-a898-b4ec805b2fea&filename=littelfuse-xtremeguard-axgd-datasheet"
				(at 25.4 -15.24 0)
				(effects
					(font
						(size 1.27 1.27)
						(thickness 0.15)
					)
					(justify left bottom)
					(hide yes)
				)
			)
			(property "Description" "Bidirectional TVS, 30 kV,  0402, 24 V, 0.04 pF"
				(at 0 0 0)
				(effects
					(font
						(size 1.27 1.27)
					)
					(hide yes)
				)
			)
			(property "Manufacturer" "Littelfuse"
				(at 25.4 -17.78 0)
				(effects
					(font
						(size 1.27 1.27)
						(thickness 0.15)
					)
					(justify left bottom)
					(hide yes)
				)
			)
			(property "MPN" "AXGD10402KR"
				(at 25.4 -7.62 0)
				(effects
					(font
						(size 1.27 1.27)
						(thickness 0.15)
					)
					(justify left bottom)
				)
			)
			(property "Author" "Antmicro"
				(at 25.4 -20.32 0)
				(effects
					(font
						(size 1.27 1.27)
						(thickness 0.15)
					)
					(justify left bottom)
					(hide yes)
				)
			)
			(property "License" "Apache-2.0"
				(at 25.4 -22.86 0)
				(effects
					(font
						(size 1.27 1.27)
						(thickness 0.15)
					)
					(justify left bottom)
					(hide yes)
				)
			)
			(property "ki_keywords" "DIODE, SEMICONDUCTOR, TVS, ESD"
				(at 0 0 0)
				(effects
					(font
						(size 1.27 1.27)
					)
					(hide yes)
				)
			)
			(symbol "AXGD10402KR_0_0"
				(text ""
					(at 7.62 -1.27 0)
					(effects
						(font
							(size 1.27 1.27)
						)
					)
				)
			)
			(symbol "AXGD10402KR_0_1"
				(polyline
					(pts
						(xy 0.635 0) (xy 4.445 0)
					)
					(stroke
						(width 0)
						(type default)
					)
					(fill
						(type none)
					)
				)
			)
			(symbol "AXGD10402KR_1_1"
				(polyline
					(pts
						(xy 2.54 1.016) (xy 2.159 1.016)
					)
					(stroke
						(width 0.254)
						(type default)
					)
					(fill
						(type none)
					)
				)
				(polyline
					(pts
						(xy 2.54 1.016) (xy 2.54 -1.016)
					)
					(stroke
						(width 0.254)
						(type default)
					)
					(fill
						(type none)
					)
				)
				(polyline
					(pts
						(xy 2.921 -1.016) (xy 2.54 -1.016)
					)
					(stroke
						(width 0.254)
						(type default)
					)
					(fill
						(type none)
					)
				)
				(polyline
					(pts
						(xy 1.016 -1.016) (xy 1.016 1.016) (xy 2.54 0) (xy 1.016 -1.016)
					)
					(stroke
						(width 0.254)
						(type default)
					)
					(fill
						(type outline)
					)
				)
				(polyline
					(pts
						(xy 4.064 1.016) (xy 4.064 -1.016) (xy 2.54 0) (xy 4.064 1.016)
					)
					(stroke
						(width 0.254)
						(type default)
					)
					(fill
						(type outline)
					)
				)
				(pin passive line
					(at 0 0 0)
					(length 0.635)
					(name "C"
						(effects
							(font
								(size 1.27 1.27)
							)
						)
					)
					(number "1"
						(effects
							(font
								(size 1.27 1.27)
							)
						)
					)
				)
				(pin passive line
					(at 5.08 0 180)
					(length 0.635)
					(name "A"
						(effects
							(font
								(size 1.27 1.27)
							)
						)
					)
					(number "2"
						(effects
							(font
								(size 1.27 1.27)
							)
						)
					)
				)
			)
		)
	(symbol "antmicroTVSDiodes:PESD4USB5U-TTS"
			(pin_names hide)
			(exclude_from_sim no)
			(in_bom yes)
			(on_board yes)
			(property "Reference" "D"
				(at 13.97 4.445 0)
				(effects
					(font
						(size 1.27 1.27)
						(thickness 0.15)
					)
					(justify left bottom)
				)
			)
			(property "Value" "PESD4USB5U-TTS"
				(at 13.97 -5.715 0)
				(effects
					(font
						(size 1.27 1.27)
						(thickness 0.15)
					)
					(justify left bottom)
					(hide yes)
				)
			)
			(property "Footprint" "antmicro-footprints:DFN-10_2.5x1mm"
				(at 13.97 -0.635 0)
				(effects
					(font
						(size 1.27 1.27)
						(thickness 0.15)
					)
					(justify left bottom)
					(hide yes)
				)
			)
			(property "Datasheet" "https://assets.nexperia.com/documents/data-sheet/PESD4USB5U-TTS.pdf"
				(at 13.97 -3.175 0)
				(effects
					(font
						(size 1.27 1.27)
						(thickness 0.15)
					)
					(justify left bottom)
					(hide yes)
				)
			)
			(property "Description" "TVS diode array, 15kV, DFN-10, 5 V, 0.5 pF"
				(at 0 0 0)
				(effects
					(font
						(size 1.27 1.27)
					)
					(hide yes)
				)
			)
			(property "MPN" "PESD4USB5U-TTS"
				(at 13.97 1.905 0)
				(effects
					(font
						(size 1.27 1.27)
						(thickness 0.15)
					)
					(justify left bottom)
				)
			)
			(property "Manufacturer" "Nexperia"
				(at 13.97 -8.255 0)
				(effects
					(font
						(size 1.27 1.27)
						(thickness 0.15)
					)
					(justify left bottom)
					(hide yes)
				)
			)
			(property "Author" "Antmicro"
				(at 13.97 -10.795 0)
				(effects
					(font
						(size 1.27 1.27)
						(thickness 0.15)
					)
					(justify left bottom)
					(hide yes)
				)
			)
			(property "License" "Apache-2.0"
				(at 13.97 -13.335 0)
				(effects
					(font
						(size 1.27 1.27)
						(thickness 0.15)
					)
					(justify left bottom)
					(hide yes)
				)
			)
			(property "ki_keywords" "SMT, DIODE, SEMICONDUCTOR, TVS, ESD"
				(at 0 0 0)
				(effects
					(font
						(size 1.27 1.27)
					)
					(hide yes)
				)
			)
			(symbol "PESD4USB5U-TTS_0_1"
				(polyline
					(pts
						(xy 3.81 -7.62) (xy 2.54 -7.62)
					)
					(stroke
						(width 0.254)
						(type default)
					)
					(fill
						(type none)
					)
				)
				(polyline
					(pts
						(xy 3.81 -5.08) (xy 2.54 -5.08)
					)
					(stroke
						(width 0.254)
						(type default)
					)
					(fill
						(type none)
					)
				)
				(polyline
					(pts
						(xy 3.81 -2.54) (xy 2.54 -2.54)
					)
					(stroke
						(width 0.254)
						(type default)
					)
					(fill
						(type none)
					)
				)
				(polyline
					(pts
						(xy 3.81 0) (xy 2.54 0)
					)
					(stroke
						(width 0.254)
						(type default)
					)
					(fill
						(type none)
					)
				)
				(polyline
					(pts
						(xy 5.08 -7.62) (xy 6.35 -7.62)
					)
					(stroke
						(width 0.254)
						(type default)
					)
					(fill
						(type none)
					)
				)
				(polyline
					(pts
						(xy 5.08 -5.08) (xy 6.35 -5.08)
					)
					(stroke
						(width 0.254)
						(type default)
					)
					(fill
						(type none)
					)
				)
				(polyline
					(pts
						(xy 5.08 -2.54) (xy 6.35 -2.54)
					)
					(stroke
						(width 0.254)
						(type default)
					)
					(fill
						(type none)
					)
				)
				(polyline
					(pts
						(xy 2.54 -10.16) (xy 6.35 -10.16) (xy 6.35 0) (xy 5.08 0)
					)
					(stroke
						(width 0.254)
						(type default)
					)
					(fill
						(type none)
					)
				)
			)
			(symbol "PESD4USB5U-TTS_1_1"
				(polyline
					(pts
						(xy 3.81 -8.255) (xy 3.81 -8.001) (xy 3.81 -7.239) (xy 4.064 -6.985)
					)
					(stroke
						(width 0.254)
						(type default)
					)
					(fill
						(type background)
					)
				)
				(polyline
					(pts
						(xy 3.81 -5.715) (xy 3.81 -5.461) (xy 3.81 -4.699) (xy 4.064 -4.445)
					)
					(stroke
						(width 0.254)
						(type default)
					)
					(fill
						(type background)
					)
				)
				(polyline
					(pts
						(xy 3.81 -3.175) (xy 3.81 -2.921) (xy 3.81 -2.159) (xy 4.064 -1.905)
					)
					(stroke
						(width 0.254)
						(type default)
					)
					(fill
						(type background)
					)
				)
				(polyline
					(pts
						(xy 3.81 -0.635) (xy 3.81 -0.381) (xy 3.81 0.381) (xy 4.064 0.635)
					)
					(stroke
						(width 0.254)
						(type default)
					)
					(fill
						(type background)
					)
				)
				(polyline
					(pts
						(xy 5.08 -8.255) (xy 5.08 -6.985) (xy 3.81 -7.62) (xy 5.08 -8.255)
					)
					(stroke
						(width 0.254)
						(type default)
					)
					(fill
						(type outline)
					)
				)
				(polyline
					(pts
						(xy 5.08 -5.715) (xy 5.08 -4.445) (xy 3.81 -5.08) (xy 5.08 -5.715)
					)
					(stroke
						(width 0.254)
						(type default)
					)
					(fill
						(type outline)
					)
				)
				(polyline
					(pts
						(xy 5.08 -3.175) (xy 5.08 -1.905) (xy 3.81 -2.54) (xy 5.08 -3.175)
					)
					(stroke
						(width 0.254)
						(type default)
					)
					(fill
						(type outline)
					)
				)
				(polyline
					(pts
						(xy 5.08 -0.635) (xy 5.08 0.635) (xy 3.81 0) (xy 5.08 -0.635)
					)
					(stroke
						(width 0.254)
						(type default)
					)
					(fill
						(type outline)
					)
				)
				(rectangle
					(start 2.54 1.27)
					(end 7.62 -11.43)
					(stroke
						(width 0.254)
						(type default)
					)
					(fill
						(type background)
					)
				)
				(circle
					(center 6.35 -7.62)
					(radius 0.127)
					(stroke
						(width 0.254)
						(type default)
					)
					(fill
						(type background)
					)
				)
				(circle
					(center 6.35 -5.08)
					(radius 0.127)
					(stroke
						(width 0.254)
						(type default)
					)
					(fill
						(type background)
					)
				)
				(circle
					(center 6.35 -2.54)
					(radius 0.127)
					(stroke
						(width 0.254)
						(type default)
					)
					(fill
						(type background)
					)
				)
				(pin passive line
					(at 0 0 0)
					(length 2.54)
					(name "1"
						(effects
							(font
								(size 1.27 1.27)
							)
						)
					)
					(number "1"
						(effects
							(font
								(size 1.27 1.27)
							)
						)
					)
				)
				(pin passive line
					(at 0 0 0)
					(length 2.54) hide
					(name "10"
						(effects
							(font
								(size 1.27 1.27)
							)
						)
					)
					(number "10"
						(effects
							(font
								(size 1.27 1.27)
							)
						)
					)
				)
				(pin passive line
					(at 0 -2.54 0)
					(length 2.54)
					(name "2"
						(effects
							(font
								(size 1.27 1.27)
							)
						)
					)
					(number "2"
						(effects
							(font
								(size 1.27 1.27)
							)
						)
					)
				)
				(pin passive line
					(at 0 -10.16 0)
					(length 2.54)
					(name "3"
						(effects
							(font
								(size 1.27 1.27)
							)
						)
					)
					(number "3"
						(effects
							(font
								(size 1.27 1.27)
							)
						)
					)
				)
				(pin passive line
					(at 0 -5.08 0)
					(length 2.54)
					(name "4"
						(effects
							(font
								(size 1.27 1.27)
							)
						)
					)
					(number "4"
						(effects
							(font
								(size 1.27 1.27)
							)
						)
					)
				)
				(pin passive line
					(at 0 -7.62 0)
					(length 2.54)
					(name "5"
						(effects
							(font
								(size 1.27 1.27)
							)
						)
					)
					(number "5"
						(effects
							(font
								(size 1.27 1.27)
							)
						)
					)
				)
				(pin passive line
					(at 0 -7.62 0)
					(length 2.54) hide
					(name "6"
						(effects
							(font
								(size 1.27 1.27)
							)
						)
					)
					(number "6"
						(effects
							(font
								(size 1.27 1.27)
							)
						)
					)
				)
				(pin passive line
					(at 0 -5.08 0)
					(length 2.54) hide
					(name "7"
						(effects
							(font
								(size 1.27 1.27)
							)
						)
					)
					(number "7"
						(effects
							(font
								(size 1.27 1.27)
							)
						)
					)
				)
				(pin passive line
					(at 0 -10.16 0)
					(length 2.54) hide
					(name "8"
						(effects
							(font
								(size 1.27 1.27)
							)
						)
					)
					(number "8"
						(effects
							(font
								(size 1.27 1.27)
							)
						)
					)
				)
				(pin passive line
					(at 0 -2.54 0)
					(length 2.54) hide
					(name "9"
						(effects
							(font
								(size 1.27 1.27)
							)
						)
					)
					(number "9"
						(effects
							(font
								(size 1.27 1.27)
							)
						)
					)
				)
			)
		)
	(symbol "antmicroTestPoints:TP_1.5mm_SMD"
			(pin_names hide)
			(exclude_from_sim no)
			(in_bom no)
			(on_board yes)
			(property "Reference" "TP"
				(at 15.24 -5.08 0)
				(effects
					(font
						(size 1.27 1.27)
						(thickness 0.15)
					)
					(justify left bottom)
				)
			)
			(property "Value" "TP_1.5mm_SMD"
				(at 15.24 -7.62 0)
				(effects
					(font
						(size 1.27 1.27)
						(thickness 0.15)
					)
					(justify left bottom)
					(hide yes)
				)
			)
			(property "Footprint" "antmicro-footprints:TP_SMD_1.5mm"
				(at 15.24 -10.16 0)
				(effects
					(font
						(size 1.27 1.27)
						(thickness 0.15)
					)
					(justify left bottom)
					(hide yes)
				)
			)
			(property "Datasheet" ""
				(at 17.78 -12.7 0)
				(effects
					(font
						(size 1.27 1.27)
						(thickness 0.15)
					)
					(justify left bottom)
					(hide yes)
				)
			)
			(property "Description" "test point, SMT"
				(at 0 0 0)
				(effects
					(font
						(size 1.27 1.27)
					)
					(hide yes)
				)
			)
			(property "MPN" ""
				(at 0 0 0)
				(effects
					(font
						(size 1.27 1.27)
					)
					(hide yes)
				)
			)
			(property "Manufacturer" ""
				(at 0 0 0)
				(effects
					(font
						(size 1.27 1.27)
					)
					(hide yes)
				)
			)
			(property "Author" "Antmicro"
				(at 15.24 -15.24 0)
				(effects
					(font
						(size 1.27 1.27)
						(thickness 0.15)
					)
					(justify left bottom)
					(hide yes)
				)
			)
			(property "License" "Apache-2.0"
				(at 15.24 -17.78 0)
				(effects
					(font
						(size 1.27 1.27)
						(thickness 0.15)
					)
					(justify left bottom)
					(hide yes)
				)
			)
			(property "ki_keywords" "TESTPOINT"
				(at 0 0 0)
				(effects
					(font
						(size 1.27 1.27)
					)
					(hide yes)
				)
			)
			(symbol "TP_1.5mm_SMD_1_1"
				(circle
					(center 3.175 0)
					(radius 0.635)
					(stroke
						(width 0.254)
						(type default)
					)
					(fill
						(type none)
					)
				)
				(pin passive line
					(at 0 0 0)
					(length 2.54)
					(name "1"
						(effects
							(font
								(size 1.27 1.27)
							)
						)
					)
					(number "1"
						(effects
							(font
								(size 1.27 1.27)
							)
						)
					)
				)
			)
		)
	(symbol "antmicroTransistorsFETsMOSFETsSingle:DMG1012T-7"
			(pin_names
				(offset 0)
			)
			(exclude_from_sim no)
			(in_bom no)
			(on_board yes)
			(property "Reference" "Q"
				(at 10.16 3.81 0)
				(effects
					(font
						(size 1.27 1.27)
						(thickness 0.15)
					)
					(justify left bottom)
				)
			)
			(property "Value" "DMG1012T-7"
				(at 10.16 -3.81 0)
				(effects
					(font
						(size 1.27 1.27)
						(thickness 0.15)
					)
					(justify left bottom)
					(hide yes)
				)
			)
			(property "Footprint" "antmicro-footprints:SOT-523"
				(at 10.16 -6.35 0)
				(effects
					(font
						(size 1.27 1.27)
						(thickness 0.15)
					)
					(justify left bottom)
					(hide yes)
				)
			)
			(property "Datasheet" "https://www.diodes.com/assets/Datasheets/ds31783.pdf"
				(at 10.16 -8.89 0)
				(effects
					(font
						(size 1.27 1.27)
						(thickness 0.15)
					)
					(justify left bottom)
					(hide yes)
				)
			)
			(property "Description" "Power MOSFET, N Channel, 20 V, 630 mA, 0.3 ohm, SOT-523, Surface Mount"
				(at 0 0 0)
				(effects
					(font
						(size 1.27 1.27)
					)
					(hide yes)
				)
			)
			(property "MPN" "DMG1012T-7"
				(at 10.16 1.27 0)
				(effects
					(font
						(size 1.27 1.27)
						(thickness 0.15)
					)
					(justify left bottom)
				)
			)
			(property "Manufacturer" "Diodes Incorporated"
				(at 10.16 -1.27 0)
				(effects
					(font
						(size 1.27 1.27)
						(thickness 0.15)
					)
					(justify left bottom)
					(hide yes)
				)
			)
			(property "Author" "Antmicro"
				(at 10.16 -11.43 0)
				(effects
					(font
						(size 1.27 1.27)
						(thickness 0.15)
					)
					(justify left bottom)
					(hide yes)
				)
			)
			(property "License" "Apache-2.0"
				(at 10.16 -13.97 0)
				(effects
					(font
						(size 1.27 1.27)
						(thickness 0.15)
					)
					(justify left bottom)
					(hide yes)
				)
			)
			(property "ki_keywords" "SMT, MOSFET, SEMICONDUCTOR"
				(at 0 0 0)
				(effects
					(font
						(size 1.27 1.27)
					)
					(hide yes)
				)
			)
			(symbol "DMG1012T-7_1_1"
				(polyline
					(pts
						(xy 3.81 1.143) (xy 3.81 0.635)
					)
					(stroke
						(width 0.254)
						(type default)
					)
					(fill
						(type background)
					)
				)
				(polyline
					(pts
						(xy 3.81 1.143) (xy 3.81 1.651)
					)
					(stroke
						(width 0.254)
						(type default)
					)
					(fill
						(type background)
					)
				)
				(polyline
					(pts
						(xy 3.81 2.54) (xy 3.81 2.032)
					)
					(stroke
						(width 0.254)
						(type default)
					)
					(fill
						(type background)
					)
				)
				(polyline
					(pts
						(xy 3.81 2.54) (xy 3.81 3.048)
					)
					(stroke
						(width 0.254)
						(type default)
					)
					(fill
						(type background)
					)
				)
				(polyline
					(pts
						(xy 3.81 4.445) (xy 3.81 3.429)
					)
					(stroke
						(width 0.254)
						(type default)
					)
					(fill
						(type background)
					)
				)
				(polyline
					(pts
						(xy 6.35 1.143) (xy 3.81 1.143)
					)
					(stroke
						(width 0.254)
						(type default)
					)
					(fill
						(type background)
					)
				)
				(polyline
					(pts
						(xy 7.874 3.048) (xy 6.858 3.048)
					)
					(stroke
						(width 0.254)
						(type default)
					)
					(fill
						(type background)
					)
				)
				(polyline
					(pts
						(xy 1.27 0) (xy 3.302 0) (xy 3.302 3.937)
					)
					(stroke
						(width 0.254)
						(type default)
					)
					(fill
						(type none)
					)
				)
				(polyline
					(pts
						(xy 6.35 -1.27) (xy 6.35 2.54) (xy 3.81 2.54)
					)
					(stroke
						(width 0.254)
						(type default)
					)
					(fill
						(type none)
					)
				)
				(polyline
					(pts
						(xy 6.35 6.35) (xy 6.35 3.937) (xy 3.81 3.937)
					)
					(stroke
						(width 0.254)
						(type default)
					)
					(fill
						(type none)
					)
				)
				(polyline
					(pts
						(xy 3.81 2.54) (xy 4.572 3.048) (xy 4.572 2.032) (xy 3.81 2.54)
					)
					(stroke
						(width 0.254)
						(type default)
					)
					(fill
						(type outline)
					)
				)
				(polyline
					(pts
						(xy 7.366 3.048) (xy 6.858 2.286) (xy 7.874 2.286) (xy 7.366 3.048)
					)
					(stroke
						(width 0.254)
						(type default)
					)
					(fill
						(type outline)
					)
				)
				(polyline
					(pts
						(xy 6.223 0.635) (xy 7.366 0.635) (xy 7.366 3.937) (xy 7.366 4.445) (xy 6.223 4.445)
					)
					(stroke
						(width 0.254)
						(type default)
					)
					(fill
						(type none)
					)
				)
				(circle
					(center 5.08 2.54)
					(radius 3.302)
					(stroke
						(width 0.254)
						(type default)
					)
					(fill
						(type background)
					)
				)
				(circle
					(center 6.35 0.635)
					(radius 0.127)
					(stroke
						(width 0.254)
						(type default)
					)
					(fill
						(type background)
					)
				)
				(circle
					(center 6.35 1.143)
					(radius 0.127)
					(stroke
						(width 0.254)
						(type default)
					)
					(fill
						(type background)
					)
				)
				(circle
					(center 6.35 4.445)
					(radius 0.127)
					(stroke
						(width 0.254)
						(type default)
					)
					(fill
						(type background)
					)
				)
				(pin passive line
					(at 0 0 0)
					(length 2.54)
					(name "G"
						(effects
							(font
								(size 1.27 1.27)
							)
						)
					)
					(number "1"
						(effects
							(font
								(size 1.27 1.27)
							)
						)
					)
				)
				(pin passive line
					(at 6.35 -2.54 90)
					(length 2.54)
					(name "S"
						(effects
							(font
								(size 1.27 1.27)
							)
						)
					)
					(number "2"
						(effects
							(font
								(size 1.27 1.27)
							)
						)
					)
				)
				(pin passive line
					(at 6.35 7.62 270)
					(length 2.54)
					(name "D"
						(effects
							(font
								(size 1.27 1.27)
							)
						)
					)
					(number "3"
						(effects
							(font
								(size 1.27 1.27)
							)
						)
					)
				)
			)
		)
	(symbol "antmicropower:+12V"
			(power)
			(pin_names
				(offset 0)
			)
			(exclude_from_sim no)
			(in_bom yes)
			(on_board yes)
			(property "Reference" "#PWR"
				(at 0 -3.81 0)
				(effects
					(font
						(size 1.27 1.27)
					)
					(hide yes)
				)
			)
			(property "Value" "+12V"
				(at 0 3.556 0)
				(effects
					(font
						(size 1.27 1.27)
					)
				)
			)
			(property "Footprint" ""
				(at 0 0 0)
				(effects
					(font
						(size 1.27 1.27)
					)
					(hide yes)
				)
			)
			(property "Datasheet" ""
				(at 0 0 0)
				(effects
					(font
						(size 1.27 1.27)
					)
					(hide yes)
				)
			)
			(property "Description" ""
				(at 0 0 0)
				(effects
					(font
						(size 1.27 1.27)
					)
					(hide yes)
				)
			)
			(symbol "+12V_0_1"
				(polyline
					(pts
						(xy -0.762 1.27) (xy 0 2.54)
					)
					(stroke
						(width 0)
						(type default)
					)
					(fill
						(type none)
					)
				)
				(polyline
					(pts
						(xy 0 0) (xy 0 2.54)
					)
					(stroke
						(width 0)
						(type default)
					)
					(fill
						(type none)
					)
				)
				(polyline
					(pts
						(xy 0 2.54) (xy 0.762 1.27)
					)
					(stroke
						(width 0)
						(type default)
					)
					(fill
						(type none)
					)
				)
			)
			(symbol "+12V_1_1"
				(pin power_in line
					(at 0 0 90)
					(length 0) hide
					(name "+12V"
						(effects
							(font
								(size 1.27 1.27)
							)
						)
					)
					(number "1"
						(effects
							(font
								(size 1.27 1.27)
							)
						)
					)
				)
			)
		)
	(symbol "antmicropower:+1V2"
			(power)
			(pin_names
				(offset 0)
			)
			(exclude_from_sim no)
			(in_bom yes)
			(on_board yes)
			(property "Reference" "#PWR"
				(at 0 -3.81 0)
				(effects
					(font
						(size 1.27 1.27)
					)
					(hide yes)
				)
			)
			(property "Value" "+1V2"
				(at 0 3.556 0)
				(effects
					(font
						(size 1.27 1.27)
					)
				)
			)
			(property "Footprint" ""
				(at 0 0 0)
				(effects
					(font
						(size 1.27 1.27)
					)
					(hide yes)
				)
			)
			(property "Datasheet" ""
				(at 0 0 0)
				(effects
					(font
						(size 1.27 1.27)
					)
					(hide yes)
				)
			)
			(property "Description" ""
				(at 0 0 0)
				(effects
					(font
						(size 1.27 1.27)
					)
					(hide yes)
				)
			)
			(symbol "+1V2_0_1"
				(polyline
					(pts
						(xy -0.762 1.27) (xy 0 2.54)
					)
					(stroke
						(width 0)
						(type default)
					)
					(fill
						(type none)
					)
				)
				(polyline
					(pts
						(xy 0 0) (xy 0 2.54)
					)
					(stroke
						(width 0)
						(type default)
					)
					(fill
						(type none)
					)
				)
				(polyline
					(pts
						(xy 0 2.54) (xy 0.762 1.27)
					)
					(stroke
						(width 0)
						(type default)
					)
					(fill
						(type none)
					)
				)
			)
			(symbol "+1V2_1_1"
				(pin power_in line
					(at 0 0 90)
					(length 0) hide
					(name "+1V2"
						(effects
							(font
								(size 1.27 1.27)
							)
						)
					)
					(number "1"
						(effects
							(font
								(size 1.27 1.27)
							)
						)
					)
				)
			)
		)
	(symbol "antmicropower:+1V8"
			(power)
			(pin_numbers hide)
			(pin_names hide)
			(exclude_from_sim no)
			(in_bom yes)
			(on_board yes)
			(property "Reference" "#PWR"
				(at 15.24 -2.54 0)
				(effects
					(font
						(size 1.27 1.27)
						(thickness 0.15)
					)
					(justify left bottom)
					(hide yes)
				)
			)
			(property "Value" "+1V8"
				(at -3.175 2.54 0)
				(effects
					(font
						(size 1.27 1.27)
						(thickness 0.15)
					)
					(justify left bottom)
				)
			)
			(property "Footprint" ""
				(at 15.24 -7.62 0)
				(effects
					(font
						(size 1.27 1.27)
						(thickness 0.15)
					)
					(justify left bottom)
					(hide yes)
				)
			)
			(property "Datasheet" ""
				(at 15.24 -10.16 0)
				(effects
					(font
						(size 1.27 1.27)
						(thickness 0.15)
					)
					(justify left bottom)
					(hide yes)
				)
			)
			(property "Description" ""
				(at 0 0 0)
				(effects
					(font
						(size 1.27 1.27)
					)
					(hide yes)
				)
			)
			(property "Author" "Antmicro"
				(at 15.24 -5.08 0)
				(effects
					(font
						(size 1.27 1.27)
						(thickness 0.15)
					)
					(justify left bottom)
					(hide yes)
				)
			)
			(property "License" "Apache-2.0"
				(at 15.24 -7.62 0)
				(effects
					(font
						(size 1.27 1.27)
						(thickness 0.15)
					)
					(justify left bottom)
					(hide yes)
				)
			)
			(symbol "+1V8_1_1"
				(polyline
					(pts
						(xy -0.762 1.27) (xy 0 2.54)
					)
					(stroke
						(width 0)
						(type default)
					)
					(fill
						(type background)
					)
				)
				(polyline
					(pts
						(xy 0 0) (xy 0 2.54)
					)
					(stroke
						(width 0)
						(type default)
					)
					(fill
						(type background)
					)
				)
				(polyline
					(pts
						(xy 0 2.54) (xy 0.762 1.27)
					)
					(stroke
						(width 0)
						(type default)
					)
					(fill
						(type background)
					)
				)
				(pin power_in line
					(at 0 0 90)
					(length 0) hide
					(name "+1V8"
						(effects
							(font
								(size 1.27 1.27)
							)
						)
					)
					(number "1"
						(effects
							(font
								(size 1.27 1.27)
							)
						)
					)
				)
			)
		)
	(symbol "antmicropower:+3V3"
			(power)
			(pin_numbers hide)
			(pin_names hide)
			(exclude_from_sim no)
			(in_bom yes)
			(on_board yes)
			(property "Reference" "#PWR"
				(at 15.24 0 0)
				(effects
					(font
						(size 1.27 1.27)
						(thickness 0.15)
					)
					(justify left bottom)
					(hide yes)
				)
			)
			(property "Value" "+3V3"
				(at -3.175 2.54 0)
				(effects
					(font
						(size 1.27 1.27)
						(thickness 0.15)
					)
					(justify left bottom)
				)
			)
			(property "Footprint" ""
				(at 15.24 -7.62 0)
				(effects
					(font
						(size 1.27 1.27)
						(thickness 0.15)
					)
					(justify left bottom)
					(hide yes)
				)
			)
			(property "Datasheet" ""
				(at 15.24 -10.16 0)
				(effects
					(font
						(size 1.27 1.27)
						(thickness 0.15)
					)
					(justify left bottom)
					(hide yes)
				)
			)
			(property "Description" ""
				(at 0 0 0)
				(effects
					(font
						(size 1.27 1.27)
					)
					(hide yes)
				)
			)
			(property "Author" "Antmicro"
				(at 15.24 -2.54 0)
				(effects
					(font
						(size 1.27 1.27)
						(thickness 0.15)
					)
					(justify left bottom)
					(hide yes)
				)
			)
			(property "License" "Apache-2.0"
				(at 15.24 -5.08 0)
				(effects
					(font
						(size 1.27 1.27)
						(thickness 0.15)
					)
					(justify left bottom)
					(hide yes)
				)
			)
			(symbol "+3V3_0_1"
				(polyline
					(pts
						(xy 0 0) (xy 0 2.54)
					)
					(stroke
						(width 0)
						(type default)
					)
					(fill
						(type none)
					)
				)
				(polyline
					(pts
						(xy 0 2.54) (xy -0.762 1.27)
					)
					(stroke
						(width 0)
						(type default)
					)
					(fill
						(type none)
					)
				)
				(polyline
					(pts
						(xy 0 2.54) (xy 0.762 1.27)
					)
					(stroke
						(width 0)
						(type default)
					)
					(fill
						(type none)
					)
				)
			)
			(symbol "+3V3_1_1"
				(pin power_in line
					(at 0 0 90)
					(length 0) hide
					(name "+3V3"
						(effects
							(font
								(size 1.27 1.27)
							)
						)
					)
					(number "1"
						(effects
							(font
								(size 1.27 1.27)
							)
						)
					)
				)
			)
		)
	(symbol "antmicropower:+5V"
			(power)
			(pin_numbers hide)
			(pin_names hide)
			(exclude_from_sim no)
			(in_bom yes)
			(on_board yes)
			(property "Reference" "#PWR"
				(at 15.24 -2.54 0)
				(effects
					(font
						(size 1.27 1.27)
						(thickness 0.15)
					)
					(justify left bottom)
					(hide yes)
				)
			)
			(property "Value" "+5V"
				(at 15.24 -5.08 0)
				(effects
					(font
						(size 1.27 1.27)
						(thickness 0.15)
					)
					(justify left bottom)
				)
			)
			(property "Footprint" ""
				(at 15.24 -7.62 0)
				(effects
					(font
						(size 1.27 1.27)
						(thickness 0.15)
					)
					(justify left bottom)
					(hide yes)
				)
			)
			(property "Datasheet" ""
				(at 15.24 -10.16 0)
				(effects
					(font
						(size 1.27 1.27)
						(thickness 0.15)
					)
					(justify left bottom)
					(hide yes)
				)
			)
			(property "Description" ""
				(at 0 0 0)
				(effects
					(font
						(size 1.27 1.27)
					)
					(hide yes)
				)
			)
			(property "Author" "Antmicro"
				(at 15.24 -7.62 0)
				(effects
					(font
						(size 1.27 1.27)
						(thickness 0.15)
					)
					(justify left bottom)
					(hide yes)
				)
			)
			(property "License" "Apache-2.0"
				(at 15.24 -10.16 0)
				(effects
					(font
						(size 1.27 1.27)
						(thickness 0.15)
					)
					(justify left bottom)
					(hide yes)
				)
			)
			(symbol "+5V_1_1"
				(polyline
					(pts
						(xy -0.762 1.27) (xy 0 2.54)
					)
					(stroke
						(width 0)
						(type default)
					)
					(fill
						(type background)
					)
				)
				(polyline
					(pts
						(xy 0 0) (xy 0 2.54)
					)
					(stroke
						(width 0)
						(type default)
					)
					(fill
						(type background)
					)
				)
				(polyline
					(pts
						(xy 0 2.54) (xy 0.762 1.27)
					)
					(stroke
						(width 0)
						(type default)
					)
					(fill
						(type background)
					)
				)
				(pin power_in line
					(at 0 0 90)
					(length 0)
					(name "+5V"
						(effects
							(font
								(size 1.27 1.27)
							)
						)
					)
					(number "1"
						(effects
							(font
								(size 1.27 1.27)
							)
						)
					)
				)
			)
		)
	(symbol "antmicropower:GND"
			(power)
			(pin_numbers hide)
			(pin_names hide)
			(exclude_from_sim no)
			(in_bom yes)
			(on_board yes)
			(property "Reference" "#PWR"
				(at 8.89 -2.54 0)
				(effects
					(font
						(size 1.27 1.27)
						(thickness 0.15)
					)
					(justify left bottom)
					(hide yes)
				)
			)
			(property "Value" "GND"
				(at 8.89 -5.08 0)
				(effects
					(font
						(size 1.27 1.27)
						(thickness 0.15)
					)
					(justify left bottom)
				)
			)
			(property "Footprint" ""
				(at 8.89 -7.62 0)
				(effects
					(font
						(size 1.27 1.27)
						(thickness 0.15)
					)
					(justify left bottom)
					(hide yes)
				)
			)
			(property "Datasheet" ""
				(at 8.89 -12.7 0)
				(effects
					(font
						(size 1.27 1.27)
						(thickness 0.15)
					)
					(justify left bottom)
					(hide yes)
				)
			)
			(property "Description" ""
				(at 0 0 0)
				(effects
					(font
						(size 1.27 1.27)
					)
					(hide yes)
				)
			)
			(property "Author" "Antmicro"
				(at 8.89 -7.62 0)
				(effects
					(font
						(size 1.27 1.27)
						(thickness 0.15)
					)
					(justify left bottom)
					(hide yes)
				)
			)
			(property "License" "Apache-2.0"
				(at 8.89 -10.16 0)
				(effects
					(font
						(size 1.27 1.27)
						(thickness 0.15)
					)
					(justify left bottom)
					(hide yes)
				)
			)
			(symbol "GND_1_1"
				(polyline
					(pts
						(xy 0 0) (xy 0 -1.27) (xy 1.27 -1.27) (xy 0 -2.54) (xy -1.27 -1.27) (xy 0 -1.27)
					)
					(stroke
						(width 0)
						(type default)
					)
					(fill
						(type none)
					)
				)
				(pin power_in line
					(at 0 0 270)
					(length 0)
					(name "GND"
						(effects
							(font
								(size 1.27 1.27)
							)
						)
					)
					(number "1"
						(effects
							(font
								(size 1.27 1.27)
							)
						)
					)
				)
			)
		)
	(symbol "antmicropower:PWR_FLAG"
			(power)
			(pin_numbers hide)
			(pin_names
				(offset 0) hide)
			(exclude_from_sim no)
			(in_bom yes)
			(on_board yes)
			(property "Reference" "#FLG"
				(at 0 1.905 0)
				(effects
					(font
						(size 1.27 1.27)
					)
					(hide yes)
				)
			)
			(property "Value" "PWR_FLAG"
				(at 0 3.81 0)
				(effects
					(font
						(size 1.27 1.27)
					)
				)
			)
			(property "Footprint" ""
				(at 0 0 0)
				(effects
					(font
						(size 1.27 1.27)
					)
					(hide yes)
				)
			)
			(property "Datasheet" ""
				(at 0 0 0)
				(effects
					(font
						(size 1.27 1.27)
					)
					(hide yes)
				)
			)
			(property "Description" ""
				(at 0 0 0)
				(effects
					(font
						(size 1.27 1.27)
					)
					(hide yes)
				)
			)
			(symbol "PWR_FLAG_0_0"
				(pin power_out line
					(at 0 0 90)
					(length 0)
					(name "pwr"
						(effects
							(font
								(size 1.27 1.27)
							)
						)
					)
					(number "1"
						(effects
							(font
								(size 1.27 1.27)
							)
						)
					)
				)
			)
			(symbol "PWR_FLAG_0_1"
				(polyline
					(pts
						(xy 0 0) (xy 0 1.27) (xy -1.016 1.905) (xy 0 2.54) (xy 1.016 1.905) (xy 0 1.27)
					)
					(stroke
						(width 0)
						(type default)
					)
					(fill
						(type none)
					)
				)
			)
		)
)
